FILE_TYPE = MACRO_DRAWING;
SET COLOR_WIRE YELLOW;
SET COLOR_PROP ORANGE;
SET COLOR_DOT WHITE;
SET COLOR_ARC YELLOW;
SET COLOR_BODY GREEN;
SET COLOR_NOTE PURPLE;
SET PROP_DISPLAY VALUE;
SET PAGE_NUMBER P334;
FORCEADD Q_RES..2
(-4950 2725);
FORCEPROP 1 LAST LOCATION R3457
J 0
(-4905 2850);
DISPLAY 0.978723 (-4905 2850);
FORCEPROP 0 LAST $SEC 1
J 0
(-4900 2900);
DISPLAY 0.680851 (-4900 2900);
PAINT MONO (-4900 2900);
DISPLAY INVISIBLE (-4900 2900);
FORCEPROP 0 LAST CDS_SEC 1
J 0
(-4900 2900);
DISPLAY 1.021277 (-4900 2900);
DISPLAY INVISIBLE (-4900 2900);
FORCEPROP 1 LASTPIN (-4950 2825) $PN 1
J 0
(-4945 2787);
DISPLAY 0.787234 (-4945 2787);
PAINT MONO (-4945 2787);
FORCEPROP 1 LASTPIN (-4950 2625) $PN 2
J 0
(-4945 2635);
DISPLAY 0.787234 (-4945 2635);
PAINT MONO (-4945 2635);
FORCEPROP 1 LAST PACK_TYPE 0402LF
J 0
(-4910 2550);
DISPLAY 0.510638 (-4910 2550);
FORCEPROP 1 LAST VALUE 10K
J 0
(-4905 2800);
DISPLAY 0.510638 (-4905 2800);
FORCEPROP 1 LAST TOLERANCE 1%
J 0
(-4905 2750);
DISPLAY 0.510638 (-4905 2750);
FORCEPROP 1 LAST WATTAGE 1/16W
J 0
(-4910 2700);
DISPLAY 0.510638 (-4910 2700);
FORCEPROP 1 LAST MATERIAL CHIP
J 0
(-4910 2650);
DISPLAY 0.510638 (-4910 2650);
FORCEPROP 2 LAST CDS_LIB pure_quanta
J 0
(-4950 2725);
DISPLAY INVISIBLE (-4950 2725);
FORCEPROP 1 LAST PATH I123
J 0
(-4900 2900);
DISPLAY 0.978723 (-4900 2900);
PAINT WHITE (-4900 2900);
DISPLAY INVISIBLE (-4900 2900);
FORCEPROP 1 LAST PART_NUMBER CS31002FB08
J 0
(-4910 2600);
DISPLAY 0.510638 (-4910 2600);
DISPLAY INVISIBLE (-4910 2600);
FORCEADD Q_RES..2
(-4975 3225);
FORCEPROP 1 LAST LOCATION R3456
J 0
(-4930 3350);
DISPLAY 0.978723 (-4930 3350);
FORCEPROP 0 LAST $SEC 1
J 0
(-4925 3400);
DISPLAY 0.680851 (-4925 3400);
PAINT MONO (-4925 3400);
DISPLAY INVISIBLE (-4925 3400);
FORCEPROP 0 LAST CDS_SEC 1
J 0
(-4925 3400);
DISPLAY 1.021277 (-4925 3400);
DISPLAY INVISIBLE (-4925 3400);
FORCEPROP 1 LASTPIN (-4975 3325) $PN 1
J 0
(-4970 3287);
DISPLAY 0.787234 (-4970 3287);
PAINT MONO (-4970 3287);
FORCEPROP 1 LASTPIN (-4975 3125) $PN 2
J 0
(-4970 3135);
DISPLAY 0.787234 (-4970 3135);
PAINT MONO (-4970 3135);
FORCEPROP 1 LAST VALUE 100K
J 0
(-4930 3300);
DISPLAY 0.510638 (-4930 3300);
FORCEPROP 1 LAST TOLERANCE 1%
J 0
(-4930 3250);
DISPLAY 0.510638 (-4930 3250);
FORCEPROP 1 LAST PACK_TYPE 0402LF
J 0
(-4935 3050);
DISPLAY 0.510638 (-4935 3050);
FORCEPROP 1 LAST WATTAGE 1/16W
J 0
(-4935 3200);
DISPLAY 0.510638 (-4935 3200);
FORCEPROP 1 LAST MATERIAL EMPTY
J 0
(-4935 3150);
DISPLAY 0.510638 (-4935 3150);
PAINT RED (-4935 3150);
FORCEPROP 2 LAST CDS_LIB pure_quanta
J 0
(-4975 3225);
DISPLAY INVISIBLE (-4975 3225);
FORCEPROP 1 LAST PATH I124
J 0
(-4925 3400);
DISPLAY 0.978723 (-4925 3400);
PAINT WHITE (-4925 3400);
DISPLAY INVISIBLE (-4925 3400);
FORCEPROP 1 LAST PART_NUMBER CS41002FB09
J 0
(-4935 3100);
DISPLAY 0.510638 (-4935 3100);
DISPLAY INVISIBLE (-4935 3100);
FORCEADD UNIVERSAL_POWER..1
(-4975 3525);
FORCEPROP 3 LASTPIN (-4975 3475) SIG_NAME P3V3_AUX\g
J 0
(-4965 3485);
DISPLAY 0.659574 (-4965 3485);
PAINT MONO (-4965 3485);
DISPLAY INVISIBLE (-4965 3485);
FORCEPROP 1 LAST HDL_POWER P3V3_AUX
J 1
(-4975 3575);
DISPLAY 0.872340 (-4975 3575);
PAINT GREEN (-4975 3575);
FORCEPROP 2 LAST CDS_LIB pure_quanta_power
J 0
(-4975 3525);
DISPLAY INVISIBLE (-4975 3525);
FORCEPROP 1 LAST PATH I125
J 0
(-4925 3550);
DISPLAY 0.872340 (-4925 3550);
PAINT AQUA (-4925 3550);
DISPLAY INVISIBLE (-4925 3550);
FORCEADD UNIVERSAL_GND..1
(-4950 2500);
FORCEPROP 3 LASTPIN (-4950 2550) SIG_NAME GND\g
J 0
(-4940 2560);
DISPLAY 0.659574 (-4940 2560);
PAINT MONO (-4940 2560);
DISPLAY INVISIBLE (-4940 2560);
FORCEPROP 2 LAST CDS_LIB pure_quanta_power
J 0
(-4950 2500);
DISPLAY INVISIBLE (-4950 2500);
FORCEPROP 1 LAST HDL_POWER GND
J 1
(-4925 2425);
DISPLAY 0.872340 (-4925 2425);
PAINT GREEN (-4925 2425);
DISPLAY INVISIBLE (-4925 2425);
FORCEPROP 1 LAST PATH I126
J 0
(-4875 2500);
DISPLAY 0.872340 (-4875 2500);
PAINT AQUA (-4875 2500);
DISPLAY INVISIBLE (-4875 2500);
FORCEADD Q_RES..2
(-7600 3350);
FORCEPROP 1 LAST LOCATION R3451
J 0
(-7555 3475);
DISPLAY 0.978723 (-7555 3475);
FORCEPROP 0 LAST $SEC 1
J 0
(-7550 3525);
DISPLAY 0.680851 (-7550 3525);
PAINT MONO (-7550 3525);
DISPLAY INVISIBLE (-7550 3525);
FORCEPROP 0 LAST CDS_SEC 1
J 0
(-7550 3525);
DISPLAY 1.021277 (-7550 3525);
DISPLAY INVISIBLE (-7550 3525);
FORCEPROP 1 LASTPIN (-7600 3450) $PN 1
J 0
(-7595 3412);
DISPLAY 0.787234 (-7595 3412);
PAINT MONO (-7595 3412);
FORCEPROP 1 LASTPIN (-7600 3250) $PN 2
J 0
(-7595 3260);
DISPLAY 0.787234 (-7595 3260);
PAINT MONO (-7595 3260);
FORCEPROP 1 LAST PACK_TYPE 0402LF
J 0
(-7560 3225);
DISPLAY 0.638298 (-7560 3225);
FORCEPROP 1 LAST TOLERANCE 5%
J 0
(-7555 3375);
DISPLAY 0.638298 (-7555 3375);
FORCEPROP 1 LAST WATTAGE 1/16W
J 0
(-7560 3325);
DISPLAY 0.638298 (-7560 3325);
FORCEPROP 1 LAST MATERIAL EMPTY
J 0
(-7560 3275);
DISPLAY 0.638298 (-7560 3275);
PAINT RED (-7560 3275);
FORCEPROP 1 LAST VALUE 4.7K
J 0
(-7555 3425);
DISPLAY 0.638298 (-7555 3425);
FORCEPROP 2 LAST CDS_LIB pure_quanta
J 0
(-7600 3350);
DISPLAY INVISIBLE (-7600 3350);
FORCEPROP 1 LAST PATH I127
J 0
(-7550 3525);
DISPLAY 0.978723 (-7550 3525);
PAINT WHITE (-7550 3525);
DISPLAY INVISIBLE (-7550 3525);
FORCEPROP 1 LAST PART_NUMBER CS24702JB10
J 0
(-7560 3175);
DISPLAY 0.638298 (-7560 3175);
DISPLAY INVISIBLE (-7560 3175);
FORCEADD UNIVERSAL_GND..1
(-6225 1050);
FORCEPROP 3 LASTPIN (-6225 1100) SIG_NAME GND\g
J 0
(-6215 1110);
DISPLAY 0.659574 (-6215 1110);
PAINT MONO (-6215 1110);
DISPLAY INVISIBLE (-6215 1110);
FORCEPROP 2 LAST CDS_LIB pure_quanta_power
J 0
(-6225 1050);
DISPLAY INVISIBLE (-6225 1050);
FORCEPROP 1 LAST HDL_POWER GND
J 1
(-6200 975);
DISPLAY 0.872340 (-6200 975);
PAINT GREEN (-6200 975);
DISPLAY INVISIBLE (-6200 975);
FORCEPROP 1 LAST PATH I137
J 0
(-6150 1050);
DISPLAY 0.872340 (-6150 1050);
PAINT AQUA (-6150 1050);
DISPLAY INVISIBLE (-6150 1050);
FORCEADD UNIVERSAL_GND..1
(-4950 750);
FORCEPROP 3 LASTPIN (-4950 800) SIG_NAME GND\g
J 0
(-4940 810);
DISPLAY 0.659574 (-4940 810);
PAINT MONO (-4940 810);
DISPLAY INVISIBLE (-4940 810);
FORCEPROP 2 LAST CDS_LIB pure_quanta_power
J 0
(-4950 750);
DISPLAY INVISIBLE (-4950 750);
FORCEPROP 1 LAST HDL_POWER GND
J 1
(-4925 675);
DISPLAY 0.872340 (-4925 675);
PAINT GREEN (-4925 675);
DISPLAY INVISIBLE (-4925 675);
FORCEPROP 1 LAST PATH I138
J 0
(-4875 750);
DISPLAY 0.872340 (-4875 750);
PAINT AQUA (-4875 750);
DISPLAY INVISIBLE (-4875 750);
FORCEADD Q_RES..2
(-4950 975);
FORCEPROP 1 LAST LOCATION R3455
J 0
(-4905 1100);
DISPLAY 0.978723 (-4905 1100);
FORCEPROP 0 LAST $SEC 1
J 0
(-4900 1150);
DISPLAY 0.680851 (-4900 1150);
PAINT MONO (-4900 1150);
DISPLAY INVISIBLE (-4900 1150);
FORCEPROP 0 LAST CDS_SEC 1
J 0
(-4900 1150);
DISPLAY 1.021277 (-4900 1150);
DISPLAY INVISIBLE (-4900 1150);
FORCEPROP 1 LASTPIN (-4950 1075) $PN 1
J 0
(-4945 1037);
DISPLAY 0.787234 (-4945 1037);
PAINT MONO (-4945 1037);
FORCEPROP 1 LASTPIN (-4950 875) $PN 2
J 0
(-4945 885);
DISPLAY 0.787234 (-4945 885);
PAINT MONO (-4945 885);
FORCEPROP 1 LAST WATTAGE 1/16W
J 0
(-4910 950);
DISPLAY 0.510638 (-4910 950);
FORCEPROP 1 LAST TOLERANCE 1%
J 0
(-4905 1000);
DISPLAY 0.510638 (-4905 1000);
FORCEPROP 1 LAST VALUE 10K
J 0
(-4905 1050);
DISPLAY 0.510638 (-4905 1050);
FORCEPROP 1 LAST MATERIAL CHIP
J 0
(-4910 900);
DISPLAY 0.510638 (-4910 900);
FORCEPROP 1 LAST PACK_TYPE 0402LF
J 0
(-4910 800);
DISPLAY 0.510638 (-4910 800);
FORCEPROP 2 LAST CDS_LIB pure_quanta
J 0
(-4950 975);
DISPLAY INVISIBLE (-4950 975);
FORCEPROP 1 LAST PATH I139
J 0
(-4900 1150);
DISPLAY 0.978723 (-4900 1150);
PAINT WHITE (-4900 1150);
DISPLAY INVISIBLE (-4900 1150);
FORCEPROP 1 LAST PART_NUMBER CS31002FB08
J 0
(-4910 850);
DISPLAY 0.510638 (-4910 850);
DISPLAY INVISIBLE (-4910 850);
FORCEADD Q_RES..1
(-4625 1250);
FORCEPROP 1 LAST LOCATION R3391
J 0
(-4850 1250);
DISPLAY 0.638298 (-4850 1250);
FORCEPROP 0 LAST $SEC 1
J 0
(-4675 1350);
DISPLAY 0.680851 (-4675 1350);
PAINT MONO (-4675 1350);
DISPLAY INVISIBLE (-4675 1350);
FORCEPROP 0 LAST CDS_SEC 1
J 0
(-4675 1350);
DISPLAY 1.021277 (-4675 1350);
DISPLAY INVISIBLE (-4675 1350);
FORCEPROP 1 LASTPIN (-4725 1250) $PN 1
J 0
(-4713 1262);
DISPLAY 0.787234 (-4713 1262);
PAINT MONO (-4713 1262);
FORCEPROP 1 LASTPIN (-4525 1250) $PN 2
J 0
(-4563 1262);
DISPLAY 0.787234 (-4563 1262);
PAINT MONO (-4563 1262);
FORCEPROP 1 LAST PACK_TYPE 0402LF
J 0
(-4800 1200);
DISPLAY 0.723404 (-4800 1200);
FORCEPROP 1 LAST MATERIAL CHIP
J 0
(-4600 1200);
DISPLAY 0.723404 (-4600 1200);
FORCEPROP 1 LAST VALUE 49.9
J 2
(-4375 1250);
DISPLAY 0.723404 (-4375 1250);
FORCEPROP 1 LAST WATTAGE 1/16W
J 2
(-4225 1200);
DISPLAY 0.723404 (-4225 1200);
PAINT SKYBLUE (-4225 1200);
DISPLAY INVISIBLE (-4225 1200);
FORCEPROP 1 LAST TOLERANCE 1%
J 0
(-4150 1250);
DISPLAY 0.723404 (-4150 1250);
PAINT SKYBLUE (-4150 1250);
DISPLAY INVISIBLE (-4150 1250);
FORCEPROP 2 LAST CDS_LIB pure_quanta
J 0
(-4625 1250);
DISPLAY INVISIBLE (-4625 1250);
FORCEPROP 1 LAST PATH I140
J 0
(-4675 1400);
DISPLAY 0.978723 (-4675 1400);
PAINT WHITE (-4675 1400);
DISPLAY INVISIBLE (-4675 1400);
FORCEPROP 1 LAST PART_NUMBER CS04992FB07
J 0
(-5025 1150);
DISPLAY 0.723404 (-5025 1150);
PAINT WHITE (-5025 1150);
DISPLAY INVISIBLE (-5025 1150);
FORCEADD OFFPAGE..2
(-3425 1250);
FORCEPROP 2 LAST $XR0 122 
J 0
(-3236 1250);
DISPLAY 0.638298 (-3236 1250);
PAINT MONO (-3236 1250);
FORCEPROP 2 LAST CDS_LIB standard
J 0
(-3425 1250);
DISPLAY INVISIBLE (-3425 1250);
FORCEPROP 1 LAST OFFPAGE TRUE
J 0
(-3100 1125);
DISPLAY 0.872340 (-3100 1125);
PAINT AQUA (-3100 1125);
DISPLAY INVISIBLE (-3100 1125);
FORCEPROP 1 LAST COMMENT_BODY TRUE
J 0
(-3470 1155);
DISPLAY 0.872340 (-3470 1155);
PAINT GREEN (-3470 1155);
DISPLAY INVISIBLE (-3470 1155);
FORCEPROP 2 LAST PATH I146
J 0
(-3225 1300);
DISPLAY 1.021277 (-3225 1300);
DISPLAY INVISIBLE (-3225 1300);
FORCEADD Q_CAP..1
(-6075 2175);
FORCEPROP 1 LAST LOCATION C1957
J 0
(-6025 2275);
DISPLAY 0.787234 (-6025 2275);
FORCEPROP 2 LAST $SEC 1
J 0
(-6025 2375);
DISPLAY 0.680851 (-6025 2375);
PAINT MONO (-6025 2375);
DISPLAY INVISIBLE (-6025 2375);
FORCEPROP 2 LAST CDS_SEC 1
J 0
(-6025 2375);
DISPLAY 1.021277 (-6025 2375);
DISPLAY INVISIBLE (-6025 2375);
FORCEPROP 1 LASTPIN (-6075 2275) $PN 1
J 0
(-6065 2255);
DISPLAY 0.787234 (-6065 2255);
FORCEPROP 1 LASTPIN (-6075 2075) $PN 2
J 0
(-6065 2055);
DISPLAY 0.787234 (-6065 2055);
FORCEPROP 1 LAST VALUE 0.1UF
J 0
(-6025 2225);
DISPLAY 0.510638 (-6025 2225);
FORCEPROP 1 LAST VOLTAGE 25V
J 0
(-6025 2175);
DISPLAY 0.510638 (-6025 2175);
FORCEPROP 1 LAST PACK_TYPE 0402
J 0
(-6025 1975);
DISPLAY 0.510638 (-6025 1975);
FORCEPROP 1 LAST TOLERANCE 10%
J 0
(-6025 2125);
DISPLAY 0.510638 (-6025 2125);
FORCEPROP 1 LAST MATERIAL X7R
J 0
(-6025 2075);
DISPLAY 0.510638 (-6025 2075);
FORCEPROP 2 LAST CDS_LIB pure_quanta
J 2
(-6075 2175);
PAINT MONO (-6075 2175);
DISPLAY INVISIBLE (-6075 2175);
FORCEPROP 1 LAST PATH I148
J 0
(-6025 2325);
DISPLAY 0.978723 (-6025 2325);
PAINT WHITE (-6025 2325);
DISPLAY INVISIBLE (-6025 2325);
FORCEPROP 1 LAST PART_NUMBER CH4104K1B00
J 0
(-6025 2025);
DISPLAY 0.510638 (-6025 2025);
DISPLAY INVISIBLE (-6025 2025);
FORCEADD UNIVERSAL_GND..1
(-6075 1950);
FORCEPROP 3 LASTPIN (-6075 2000) SIG_NAME GND\g
J 0
(-6065 2010);
DISPLAY 0.659574 (-6065 2010);
PAINT MONO (-6065 2010);
DISPLAY INVISIBLE (-6065 2010);
FORCEPROP 2 LAST CDS_LIB pure_quanta_power
J 0
(-6075 1950);
PAINT MONO (-6075 1950);
DISPLAY INVISIBLE (-6075 1950);
FORCEPROP 1 LAST HDL_POWER GND
J 1
(-6050 1875);
DISPLAY 0.872340 (-6050 1875);
PAINT GREEN (-6050 1875);
DISPLAY INVISIBLE (-6050 1875);
FORCEPROP 1 LAST PATH I149
J 0
(-6000 1950);
DISPLAY 0.872340 (-6000 1950);
PAINT AQUA (-6000 1950);
DISPLAY INVISIBLE (-6000 1950);
FORCEADD 74LVC2G17GW..1
(-6250 1575);
FORCEPROP 1 LAST LOCATION U252
J 0
(-6023 1335);
DISPLAY 0.723404 (-6023 1335);
PAINT GREEN (-6023 1335);
FORCEPROP 0 LAST $SEC 1
J 0
(-6000 1375);
DISPLAY 0.680851 (-6000 1375);
PAINT MONO (-6000 1375);
DISPLAY INVISIBLE (-6000 1375);
FORCEPROP 0 LAST CDS_SEC 1
J 0
(-6000 1375);
DISPLAY 1.021277 (-6000 1375);
DISPLAY INVISIBLE (-6000 1375);
FORCEPROP 0 LASTPIN (-6625 1700) $PN 1
J 2
(-6635 1710);
DISPLAY 0.680851 (-6635 1710);
PAINT MONO (-6635 1710);
FORCEPROP 0 LASTPIN (-6625 1450) $PN 3
J 2
(-6635 1460);
DISPLAY 0.680851 (-6635 1460);
PAINT MONO (-6635 1460);
FORCEPROP 0 LASTPIN (-5875 1700) $PN 6
J 0
(-5865 1710);
DISPLAY 0.680851 (-5865 1710);
PAINT MONO (-5865 1710);
FORCEPROP 0 LASTPIN (-5875 1450) $PN 4
J 0
(-5865 1460);
DISPLAY 0.680851 (-5865 1460);
PAINT MONO (-5865 1460);
FORCEPROP 0 LASTPIN (-6225 1150) $PN 2
R 1
J 2
(-6235 1140);
DISPLAY 0.680851 (-6235 1140);
PAINT MONO (-6235 1140);
FORCEPROP 0 LASTPIN (-6225 2000) $PN 5
R 1
J 0
(-6235 2010);
DISPLAY 0.680851 (-6235 2010);
PAINT MONO (-6235 2010);
FORCEPROP 2 LAST VALUE 74LVC2G17GW
J 0
(-6800 1225);
DISPLAY 1.021277 (-6800 1225);
FORCEPROP 1 LAST MATERIAL IC
J 0
(-6800 1125);
DISPLAY 0.723404 (-6800 1125);
PAINT GREEN (-6800 1125);
FORCEPROP 2 LAST PART_TYPE SMLF
J 0
(-6800 1275);
DISPLAY 1.021277 (-6800 1275);
FORCEPROP 2 LAST CDS_LIB pure_quanta
J 0
(-6250 1575);
DISPLAY INVISIBLE (-6250 1575);
FORCEPROP 1 LAST NEEDS_NO_SIZE TRUE
J 0
(-6025 1574);
DISPLAY 0.468085 (-6025 1574);
PAINT GREEN (-6025 1574);
DISPLAY INVISIBLE (-6025 1574);
FORCEPROP 1 LAST CDS_LMAN_SYM_OUTLINE -225,275,225,-275
J 0
(-6250 1575);
DISPLAY 0.468085 (-6250 1575);
PAINT GREEN (-6250 1575);
DISPLAY INVISIBLE (-6250 1575);
FORCEPROP 1 LAST PATH I153
J 0
(-6025 1300);
DISPLAY 0.723404 (-6025 1300);
PAINT GREEN (-6025 1300);
DISPLAY INVISIBLE (-6025 1300);
FORCEPROP 1 LAST PART_NUMBER AL2G0017005
J 0
(-6800 1175);
DISPLAY 0.723404 (-6800 1175);
PAINT GREEN (-6800 1175);
DISPLAY INVISIBLE (-6800 1175);
FORCEADD UNIVERSAL_POWER..1
(-6075 2500);
FORCEPROP 3 LASTPIN (-6075 2450) SIG_NAME P3V3_AUX\g
J 0
(-6065 2460);
DISPLAY 0.659574 (-6065 2460);
PAINT MONO (-6065 2460);
DISPLAY INVISIBLE (-6065 2460);
FORCEPROP 1 LAST HDL_POWER P3V3_AUX
J 1
(-6075 2550);
DISPLAY 0.872340 (-6075 2550);
PAINT GREEN (-6075 2550);
FORCEPROP 2 LAST CDS_LIB pure_quanta_power
J 0
(-6075 2500);
PAINT MONO (-6075 2500);
DISPLAY INVISIBLE (-6075 2500);
FORCEPROP 1 LAST PATH I154
J 0
(-6025 2525);
DISPLAY 0.872340 (-6025 2525);
PAINT AQUA (-6025 2525);
DISPLAY INVISIBLE (-6025 2525);
FORCEADD UNIVERSAL_GND..1
(-7575 2625);
FORCEPROP 3 LASTPIN (-7575 2675) SIG_NAME GND\g
J 0
(-7565 2685);
DISPLAY 0.659574 (-7565 2685);
PAINT MONO (-7565 2685);
DISPLAY INVISIBLE (-7565 2685);
FORCEPROP 2 LAST CDS_LIB pure_quanta_power
J 0
(-7575 2625);
DISPLAY INVISIBLE (-7575 2625);
FORCEPROP 1 LAST HDL_POWER GND
J 1
(-7550 2550);
DISPLAY 0.872340 (-7550 2550);
PAINT GREEN (-7550 2550);
DISPLAY INVISIBLE (-7550 2550);
FORCEPROP 1 LAST PATH I16
J 0
(-7500 2625);
DISPLAY 0.872340 (-7500 2625);
PAINT AQUA (-7500 2625);
DISPLAY INVISIBLE (-7500 2625);
FORCEADD OFFPAGE..2
(-3475 4125);
FORCEPROP 2 LAST $XR0 120 
J 0
(-3286 4125);
DISPLAY 0.638298 (-3286 4125);
PAINT MONO (-3286 4125);
FORCEPROP 2 LAST CDS_LIB standard
J 0
(-3475 4125);
DISPLAY INVISIBLE (-3475 4125);
FORCEPROP 1 LAST OFFPAGE TRUE
J 0
(-3150 4000);
DISPLAY 0.872340 (-3150 4000);
PAINT AQUA (-3150 4000);
DISPLAY INVISIBLE (-3150 4000);
FORCEPROP 1 LAST COMMENT_BODY TRUE
J 0
(-3520 4030);
DISPLAY 0.872340 (-3520 4030);
PAINT GREEN (-3520 4030);
DISPLAY INVISIBLE (-3520 4030);
FORCEPROP 2 LAST PATH I161
J 0
(-3275 4175);
DISPLAY 1.021277 (-3275 4175);
DISPLAY INVISIBLE (-3275 4175);
FORCEADD Q_RES..1
(-4750 4125);
FORCEPROP 1 LAST LOCATION R3390
J 0
(-4950 4125);
DISPLAY 0.723404 (-4950 4125);
FORCEPROP 2 LAST $SEC 1
J 0
(-4800 4325);
DISPLAY 0.680851 (-4800 4325);
PAINT MONO (-4800 4325);
DISPLAY INVISIBLE (-4800 4325);
FORCEPROP 0 LAST CDS_SEC 1
J 0
(-5050 4200);
DISPLAY INVISIBLE (-5050 4200);
FORCEPROP 1 LASTPIN (-4850 4125) $PN 1
J 0
(-4838 4137);
DISPLAY 0.723404 (-4838 4137);
PAINT MONO (-4838 4137);
FORCEPROP 1 LASTPIN (-4650 4125) $PN 2
J 0
(-4688 4137);
DISPLAY 0.723404 (-4688 4137);
PAINT MONO (-4688 4137);
FORCEPROP 1 LAST PACK_TYPE 0402LF
J 0
(-4925 4075);
DISPLAY 0.723404 (-4925 4075);
FORCEPROP 1 LAST MATERIAL CHIP
J 0
(-4725 4075);
DISPLAY 0.723404 (-4725 4075);
FORCEPROP 1 LAST VALUE 49.9
J 2
(-4500 4125);
DISPLAY 0.723404 (-4500 4125);
FORCEPROP 2 LAST CDS_LIB pure_quanta
J 0
(-4750 4125);
DISPLAY INVISIBLE (-4750 4125);
FORCEPROP 1 LAST TOLERANCE 1%
J 0
(-4275 4125);
DISPLAY 0.723404 (-4275 4125);
PAINT SKYBLUE (-4275 4125);
DISPLAY INVISIBLE (-4275 4125);
FORCEPROP 1 LAST WATTAGE 1/16W
J 2
(-4350 4075);
DISPLAY 0.723404 (-4350 4075);
PAINT SKYBLUE (-4350 4075);
DISPLAY INVISIBLE (-4350 4075);
FORCEPROP 1 LAST PATH I162
J 0
(-4800 4275);
DISPLAY 0.978723 (-4800 4275);
PAINT WHITE (-4800 4275);
DISPLAY INVISIBLE (-4800 4275);
FORCEPROP 1 LAST PART_NUMBER CS04992FB07
J 0
(-5150 4025);
DISPLAY 0.723404 (-5150 4025);
PAINT WHITE (-5150 4025);
DISPLAY INVISIBLE (-5150 4025);
FORCEADD UNIVERSAL_POWER..1
(-5000 4675);
FORCEPROP 3 LASTPIN (-5000 4625) SIG_NAME P3V3_AUX\g
J 0
(-4990 4635);
DISPLAY 0.659574 (-4990 4635);
PAINT MONO (-4990 4635);
DISPLAY INVISIBLE (-4990 4635);
FORCEPROP 1 LAST HDL_POWER P3V3_AUX
J 1
(-5000 4725);
DISPLAY 0.872340 (-5000 4725);
PAINT GREEN (-5000 4725);
FORCEPROP 2 LAST CDS_LIB pure_quanta_power
J 0
(-5000 4675);
PAINT MONO (-5000 4675);
DISPLAY INVISIBLE (-5000 4675);
FORCEPROP 1 LAST PATH I163
J 0
(-4950 4700);
DISPLAY 0.872340 (-4950 4700);
PAINT AQUA (-4950 4700);
DISPLAY INVISIBLE (-4950 4700);
FORCEADD Q_RES..2
(-5000 4425);
FORCEPROP 1 LAST LOCATION R3453
J 0
(-4955 4550);
DISPLAY 0.978723 (-4955 4550);
FORCEPROP 0 LAST $SEC 1
J 0
(-4950 4600);
DISPLAY 0.680851 (-4950 4600);
PAINT MONO (-4950 4600);
DISPLAY INVISIBLE (-4950 4600);
FORCEPROP 0 LAST CDS_SEC 1
J 0
(-4950 4600);
DISPLAY 1.021277 (-4950 4600);
DISPLAY INVISIBLE (-4950 4600);
FORCEPROP 1 LASTPIN (-5000 4525) $PN 1
J 0
(-4995 4487);
DISPLAY 0.787234 (-4995 4487);
PAINT MONO (-4995 4487);
FORCEPROP 1 LASTPIN (-5000 4325) $PN 2
J 0
(-4995 4335);
DISPLAY 0.787234 (-4995 4335);
PAINT MONO (-4995 4335);
FORCEPROP 1 LAST WATTAGE 1/16W
J 0
(-4960 4400);
DISPLAY 0.510638 (-4960 4400);
FORCEPROP 1 LAST TOLERANCE 1%
J 0
(-4955 4450);
DISPLAY 0.510638 (-4955 4450);
FORCEPROP 1 LAST VALUE 100K
J 0
(-4955 4500);
DISPLAY 0.510638 (-4955 4500);
FORCEPROP 1 LAST PACK_TYPE 0402LF
J 0
(-4960 4250);
DISPLAY 0.510638 (-4960 4250);
FORCEPROP 1 LAST MATERIAL EMPTY
J 0
(-4960 4350);
DISPLAY 0.510638 (-4960 4350);
PAINT RED (-4960 4350);
FORCEPROP 2 LAST CDS_LIB pure_quanta
J 0
(-5000 4425);
DISPLAY INVISIBLE (-5000 4425);
FORCEPROP 1 LAST PATH I164
J 0
(-4950 4600);
DISPLAY 0.978723 (-4950 4600);
PAINT WHITE (-4950 4600);
DISPLAY INVISIBLE (-4950 4600);
FORCEPROP 1 LAST PART_NUMBER CS41002FB09
J 0
(-4960 4300);
DISPLAY 0.510638 (-4960 4300);
DISPLAY INVISIBLE (-4960 4300);
FORCEADD Q_RES..2
(-4975 3825);
FORCEPROP 1 LAST LOCATION R3454
J 0
(-4930 3950);
DISPLAY 0.978723 (-4930 3950);
FORCEPROP 0 LAST $SEC 1
J 0
(-4925 4000);
DISPLAY 0.680851 (-4925 4000);
PAINT MONO (-4925 4000);
DISPLAY INVISIBLE (-4925 4000);
FORCEPROP 0 LAST CDS_SEC 1
J 0
(-4925 4000);
DISPLAY 1.021277 (-4925 4000);
DISPLAY INVISIBLE (-4925 4000);
FORCEPROP 1 LASTPIN (-4975 3925) $PN 1
J 0
(-4970 3887);
DISPLAY 0.787234 (-4970 3887);
PAINT MONO (-4970 3887);
FORCEPROP 1 LASTPIN (-4975 3725) $PN 2
J 0
(-4970 3735);
DISPLAY 0.787234 (-4970 3735);
PAINT MONO (-4970 3735);
FORCEPROP 1 LAST MATERIAL CHIP
J 0
(-4935 3750);
DISPLAY 0.638298 (-4935 3750);
FORCEPROP 1 LAST TOLERANCE 1%
J 0
(-4930 3850);
DISPLAY 0.638298 (-4930 3850);
FORCEPROP 1 LAST VALUE 1K
J 0
(-4930 3900);
DISPLAY 0.638298 (-4930 3900);
FORCEPROP 1 LAST WATTAGE 1/16W
J 0
(-4935 3800);
DISPLAY 0.638298 (-4935 3800);
FORCEPROP 1 LAST PACK_TYPE 0402LF
J 0
(-4935 3650);
DISPLAY 0.638298 (-4935 3650);
FORCEPROP 2 LAST CDS_LIB pure_quanta
J 0
(-4975 3825);
DISPLAY INVISIBLE (-4975 3825);
FORCEPROP 1 LAST PATH I165
J 0
(-4925 4000);
DISPLAY 0.978723 (-4925 4000);
PAINT WHITE (-4925 4000);
DISPLAY INVISIBLE (-4925 4000);
FORCEPROP 1 LAST PART_NUMBER CS21002FB06
J 0
(-4935 3700);
DISPLAY 0.638298 (-4935 3700);
DISPLAY INVISIBLE (-4935 3700);
FORCEADD UNIVERSAL_GND..1
(-4975 3625);
FORCEPROP 3 LASTPIN (-4975 3675) SIG_NAME GND\g
J 0
(-4965 3685);
DISPLAY 0.659574 (-4965 3685);
PAINT MONO (-4965 3685);
DISPLAY INVISIBLE (-4965 3685);
FORCEPROP 2 LAST CDS_LIB pure_quanta_power
J 0
(-4975 3625);
DISPLAY INVISIBLE (-4975 3625);
FORCEPROP 1 LAST HDL_POWER GND
J 1
(-4950 3550);
DISPLAY 0.872340 (-4950 3550);
PAINT GREEN (-4950 3550);
DISPLAY INVISIBLE (-4950 3550);
FORCEPROP 1 LAST PATH I166
J 0
(-4900 3625);
DISPLAY 0.872340 (-4900 3625);
PAINT AQUA (-4900 3625);
DISPLAY INVISIBLE (-4900 3625);
FORCEADD UNIVERSAL_POWER..1
(-7600 4650);
FORCEPROP 3 LASTPIN (-7600 4600) SIG_NAME P3V3_AUX\g
J 0
(-7590 4610);
DISPLAY 0.659574 (-7590 4610);
PAINT MONO (-7590 4610);
DISPLAY INVISIBLE (-7590 4610);
FORCEPROP 1 LAST HDL_POWER P3V3_AUX
J 1
(-7600 4700);
DISPLAY 0.872340 (-7600 4700);
PAINT GREEN (-7600 4700);
FORCEPROP 2 LAST CDS_LIB pure_quanta_power
J 0
(-7600 4650);
PAINT MONO (-7600 4650);
DISPLAY INVISIBLE (-7600 4650);
FORCEPROP 1 LAST PATH I167
J 0
(-7550 4675);
DISPLAY 0.872340 (-7550 4675);
PAINT AQUA (-7550 4675);
DISPLAY INVISIBLE (-7550 4675);
FORCEADD Q_RES..2
(-7600 4400);
FORCEPROP 1 LAST LOCATION R3448
J 0
(-7555 4525);
DISPLAY 0.978723 (-7555 4525);
FORCEPROP 0 LAST $SEC 1
J 0
(-7550 4575);
DISPLAY 0.680851 (-7550 4575);
PAINT MONO (-7550 4575);
DISPLAY INVISIBLE (-7550 4575);
FORCEPROP 0 LAST CDS_SEC 1
J 0
(-7550 4575);
DISPLAY 1.021277 (-7550 4575);
DISPLAY INVISIBLE (-7550 4575);
FORCEPROP 1 LASTPIN (-7600 4500) $PN 1
J 0
(-7595 4462);
DISPLAY 0.787234 (-7595 4462);
PAINT MONO (-7595 4462);
FORCEPROP 1 LASTPIN (-7600 4300) $PN 2
J 0
(-7595 4310);
DISPLAY 0.787234 (-7595 4310);
PAINT MONO (-7595 4310);
FORCEPROP 1 LAST VALUE 4.7K
J 0
(-7555 4475);
DISPLAY 0.638298 (-7555 4475);
FORCEPROP 1 LAST MATERIAL EMPTY
J 0
(-7560 4325);
DISPLAY 0.638298 (-7560 4325);
PAINT RED (-7560 4325);
FORCEPROP 1 LAST PACK_TYPE 0402LF
J 0
(-7560 4275);
DISPLAY 0.638298 (-7560 4275);
FORCEPROP 1 LAST WATTAGE 1/16W
J 0
(-7560 4375);
DISPLAY 0.638298 (-7560 4375);
FORCEPROP 1 LAST TOLERANCE 5%
J 0
(-7555 4425);
DISPLAY 0.638298 (-7555 4425);
FORCEPROP 2 LAST CDS_LIB pure_quanta
J 0
(-7600 4400);
DISPLAY INVISIBLE (-7600 4400);
FORCEPROP 1 LAST PATH I168
J 0
(-7550 4575);
DISPLAY 0.978723 (-7550 4575);
PAINT WHITE (-7550 4575);
DISPLAY INVISIBLE (-7550 4575);
FORCEPROP 1 LAST PART_NUMBER CS24702JB10
J 0
(-7560 4225);
DISPLAY 0.638298 (-7560 4225);
DISPLAY INVISIBLE (-7560 4225);
FORCEADD OFFPAGE..4
R 2
(-7850 4125);
FORCEPROP 2 LAST $XR0 81 
J 0
(-8071 4125);
DISPLAY 0.638298 (-8071 4125);
PAINT MONO (-8071 4125);
FORCEPROP 2 LAST CDS_LIB standard
J 0
(-7850 4125);
DISPLAY INVISIBLE (-7850 4125);
FORCEPROP 1 LAST OFFPAGE TRUE
J 2
(-8175 4000);
DISPLAY 0.872340 (-8175 4000);
PAINT GREEN (-8175 4000);
DISPLAY INVISIBLE (-8175 4000);
FORCEPROP 1 LAST COMMENT_BODY TRUE
J 2
(-7825 4025);
DISPLAY 0.872340 (-7825 4025);
PAINT GREEN (-7825 4025);
DISPLAY INVISIBLE (-7825 4025);
FORCEPROP 2 LAST PATH I169
J 0
(-8125 4175);
DISPLAY 1.021277 (-8125 4175);
DISPLAY INVISIBLE (-8125 4175);
FORCEADD Q_RES..2
(-7575 3925);
FORCEPROP 1 LAST LOCATION R3449
J 0
(-7530 4050);
DISPLAY 0.978723 (-7530 4050);
FORCEPROP 0 LAST $SEC 1
J 0
(-7525 4100);
DISPLAY 0.680851 (-7525 4100);
PAINT MONO (-7525 4100);
DISPLAY INVISIBLE (-7525 4100);
FORCEPROP 0 LAST CDS_SEC 1
J 0
(-7525 4100);
DISPLAY 1.021277 (-7525 4100);
DISPLAY INVISIBLE (-7525 4100);
FORCEPROP 1 LASTPIN (-7575 4025) $PN 1
J 0
(-7570 3987);
DISPLAY 0.787234 (-7570 3987);
PAINT MONO (-7570 3987);
FORCEPROP 1 LASTPIN (-7575 3825) $PN 2
J 0
(-7570 3835);
DISPLAY 0.787234 (-7570 3835);
PAINT MONO (-7570 3835);
FORCEPROP 1 LAST WATTAGE 1/16W
J 0
(-7535 3900);
DISPLAY 0.510638 (-7535 3900);
FORCEPROP 1 LAST PACK_TYPE 0402LF
J 0
(-7535 3750);
DISPLAY 0.510638 (-7535 3750);
FORCEPROP 1 LAST TOLERANCE 1%
J 0
(-7530 3950);
DISPLAY 0.510638 (-7530 3950);
FORCEPROP 1 LAST MATERIAL CHIP
J 0
(-7535 3850);
DISPLAY 0.510638 (-7535 3850);
FORCEPROP 1 LAST VALUE 100K
J 0
(-7530 4000);
DISPLAY 0.510638 (-7530 4000);
FORCEPROP 2 LAST CDS_LIB pure_quanta
J 0
(-7575 3925);
DISPLAY INVISIBLE (-7575 3925);
FORCEPROP 1 LAST PATH I170
J 0
(-7525 4100);
DISPLAY 0.978723 (-7525 4100);
PAINT WHITE (-7525 4100);
DISPLAY INVISIBLE (-7525 4100);
FORCEPROP 1 LAST PART_NUMBER CS41002FB09
J 0
(-7535 3800);
DISPLAY 0.510638 (-7535 3800);
DISPLAY INVISIBLE (-7535 3800);
FORCEADD UNIVERSAL_GND..1
(-7575 3725);
FORCEPROP 3 LASTPIN (-7575 3775) SIG_NAME GND\g
J 0
(-7565 3785);
DISPLAY 0.659574 (-7565 3785);
PAINT MONO (-7565 3785);
DISPLAY INVISIBLE (-7565 3785);
FORCEPROP 2 LAST CDS_LIB pure_quanta_power
J 0
(-7575 3725);
DISPLAY INVISIBLE (-7575 3725);
FORCEPROP 1 LAST HDL_POWER GND
J 1
(-7550 3650);
DISPLAY 0.872340 (-7550 3650);
PAINT GREEN (-7550 3650);
DISPLAY INVISIBLE (-7550 3650);
FORCEPROP 1 LAST PATH I171
J 0
(-7500 3725);
DISPLAY 0.872340 (-7500 3725);
PAINT AQUA (-7500 3725);
DISPLAY INVISIBLE (-7500 3725);
FORCEADD OFFPAGE..4
R 2
(-8300 1700);
FORCEPROP 2 LAST $XR0 85 
J 0
(-8521 1700);
DISPLAY 0.638298 (-8521 1700);
PAINT MONO (-8521 1700);
FORCEPROP 2 LAST CDS_LIB standard
J 0
(-8300 1700);
DISPLAY INVISIBLE (-8300 1700);
FORCEPROP 1 LAST OFFPAGE TRUE
J 2
(-8625 1575);
DISPLAY 0.872340 (-8625 1575);
PAINT GREEN (-8625 1575);
DISPLAY INVISIBLE (-8625 1575);
FORCEPROP 1 LAST COMMENT_BODY TRUE
J 2
(-8275 1600);
DISPLAY 0.872340 (-8275 1600);
PAINT GREEN (-8275 1600);
DISPLAY INVISIBLE (-8275 1600);
FORCEPROP 2 LAST PATH I172
J 0
(-8550 1750);
DISPLAY 1.021277 (-8550 1750);
DISPLAY INVISIBLE (-8550 1750);
FORCEADD 74LVC2G17GW..1
(-6325 -275);
FORCEPROP 1 LAST LOCATION U256
J 0
(-6098 -515);
DISPLAY 0.723404 (-6098 -515);
PAINT GREEN (-6098 -515);
FORCEPROP 0 LAST $SEC 1
J 0
(-6075 -475);
DISPLAY 0.680851 (-6075 -475);
PAINT MONO (-6075 -475);
DISPLAY INVISIBLE (-6075 -475);
FORCEPROP 0 LAST CDS_SEC 1
J 0
(-6075 -475);
DISPLAY 1.021277 (-6075 -475);
DISPLAY INVISIBLE (-6075 -475);
FORCEPROP 0 LASTPIN (-6700 -150) $PN 1
J 2
(-6710 -140);
DISPLAY 0.680851 (-6710 -140);
PAINT MONO (-6710 -140);
FORCEPROP 0 LASTPIN (-6700 -400) $PN 3
J 2
(-6710 -390);
DISPLAY 0.680851 (-6710 -390);
PAINT MONO (-6710 -390);
FORCEPROP 0 LASTPIN (-5950 -150) $PN 6
J 0
(-5940 -140);
DISPLAY 0.680851 (-5940 -140);
PAINT MONO (-5940 -140);
FORCEPROP 0 LASTPIN (-5950 -400) $PN 4
J 0
(-5940 -390);
DISPLAY 0.680851 (-5940 -390);
PAINT MONO (-5940 -390);
FORCEPROP 0 LASTPIN (-6300 -700) $PN 2
R 1
J 2
(-6310 -710);
DISPLAY 0.680851 (-6310 -710);
PAINT MONO (-6310 -710);
FORCEPROP 0 LASTPIN (-6300 150) $PN 5
R 1
J 0
(-6310 160);
DISPLAY 0.680851 (-6310 160);
PAINT MONO (-6310 160);
FORCEPROP 1 LAST MATERIAL IC
J 0
(-6900 -725);
DISPLAY 0.723404 (-6900 -725);
PAINT GREEN (-6900 -725);
FORCEPROP 2 LAST PART_TYPE SMLF
J 0
(-6900 -575);
DISPLAY 1.021277 (-6900 -575);
FORCEPROP 2 LAST VALUE 74LVC2G17GW
J 0
(-6900 -625);
DISPLAY 1.021277 (-6900 -625);
FORCEPROP 2 LAST CDS_LIB pure_quanta
J 0
(-6325 -275);
DISPLAY INVISIBLE (-6325 -275);
FORCEPROP 1 LAST NEEDS_NO_SIZE TRUE
J 0
(-6100 -276);
DISPLAY 0.468085 (-6100 -276);
PAINT GREEN (-6100 -276);
DISPLAY INVISIBLE (-6100 -276);
FORCEPROP 1 LAST CDS_LMAN_SYM_OUTLINE -225,275,225,-275
J 0
(-6325 -275);
DISPLAY 0.468085 (-6325 -275);
PAINT GREEN (-6325 -275);
DISPLAY INVISIBLE (-6325 -275);
FORCEPROP 1 LAST PATH I173
J 0
(-6100 -550);
DISPLAY 0.723404 (-6100 -550);
PAINT GREEN (-6100 -550);
DISPLAY INVISIBLE (-6100 -550);
FORCEPROP 1 LAST PART_NUMBER AL2G0017005
J 0
(-6900 -675);
DISPLAY 0.723404 (-6900 -675);
PAINT GREEN (-6900 -675);
DISPLAY INVISIBLE (-6900 -675);
FORCEADD UNIVERSAL_POWER..1
(-6175 625);
FORCEPROP 3 LASTPIN (-6175 575) SIG_NAME P3V3_AUX\g
J 0
(-6165 585);
DISPLAY 0.659574 (-6165 585);
PAINT MONO (-6165 585);
DISPLAY INVISIBLE (-6165 585);
FORCEPROP 1 LAST HDL_POWER P3V3_AUX
J 1
(-6175 675);
DISPLAY 0.872340 (-6175 675);
PAINT GREEN (-6175 675);
FORCEPROP 2 LAST CDS_LIB pure_quanta_power
J 0
(-6175 625);
PAINT MONO (-6175 625);
DISPLAY INVISIBLE (-6175 625);
FORCEPROP 1 LAST PATH I174
J 0
(-6125 650);
DISPLAY 0.872340 (-6125 650);
PAINT AQUA (-6125 650);
DISPLAY INVISIBLE (-6125 650);
FORCEADD Q_CAP..1
(-6175 300);
FORCEPROP 1 LAST LOCATION C1977
J 0
(-6125 400);
DISPLAY 0.787234 (-6125 400);
FORCEPROP 2 LAST $SEC 1
J 0
(-6125 500);
DISPLAY 0.680851 (-6125 500);
PAINT MONO (-6125 500);
DISPLAY INVISIBLE (-6125 500);
FORCEPROP 2 LAST CDS_SEC 1
J 0
(-6125 500);
DISPLAY 1.021277 (-6125 500);
DISPLAY INVISIBLE (-6125 500);
FORCEPROP 1 LASTPIN (-6175 400) $PN 1
J 0
(-6165 380);
DISPLAY 0.787234 (-6165 380);
FORCEPROP 1 LASTPIN (-6175 200) $PN 2
J 0
(-6165 180);
DISPLAY 0.787234 (-6165 180);
FORCEPROP 1 LAST TOLERANCE 10%
J 0
(-6125 250);
DISPLAY 0.510638 (-6125 250);
FORCEPROP 1 LAST PACK_TYPE 0402
J 0
(-6125 100);
DISPLAY 0.510638 (-6125 100);
FORCEPROP 1 LAST VALUE 0.1UF
J 0
(-6125 350);
DISPLAY 0.510638 (-6125 350);
FORCEPROP 1 LAST VOLTAGE 25V
J 0
(-6125 300);
DISPLAY 0.510638 (-6125 300);
FORCEPROP 1 LAST MATERIAL X7R
J 0
(-6125 200);
DISPLAY 0.510638 (-6125 200);
FORCEPROP 2 LAST CDS_LIB pure_quanta
J 2
(-6175 300);
PAINT MONO (-6175 300);
DISPLAY INVISIBLE (-6175 300);
FORCEPROP 1 LAST PATH I175
J 0
(-6125 450);
DISPLAY 0.978723 (-6125 450);
PAINT WHITE (-6125 450);
DISPLAY INVISIBLE (-6125 450);
FORCEPROP 1 LAST PART_NUMBER CH4104K1B00
J 0
(-6125 150);
DISPLAY 0.510638 (-6125 150);
DISPLAY INVISIBLE (-6125 150);
FORCEADD UNIVERSAL_GND..1
(-6175 75);
FORCEPROP 3 LASTPIN (-6175 125) SIG_NAME GND\g
J 0
(-6165 135);
DISPLAY 0.659574 (-6165 135);
PAINT MONO (-6165 135);
DISPLAY INVISIBLE (-6165 135);
FORCEPROP 2 LAST CDS_LIB pure_quanta_power
J 0
(-6175 75);
PAINT MONO (-6175 75);
DISPLAY INVISIBLE (-6175 75);
FORCEPROP 1 LAST HDL_POWER GND
J 1
(-6150 0);
DISPLAY 0.872340 (-6150 0);
PAINT GREEN (-6150 0);
DISPLAY INVISIBLE (-6150 0);
FORCEPROP 1 LAST PATH I176
J 0
(-6100 75);
DISPLAY 0.872340 (-6100 75);
PAINT AQUA (-6100 75);
DISPLAY INVISIBLE (-6100 75);
FORCEADD UNIVERSAL_GND..1
(-6300 -850);
FORCEPROP 3 LASTPIN (-6300 -800) SIG_NAME GND\g
J 0
(-6290 -790);
DISPLAY 0.659574 (-6290 -790);
PAINT MONO (-6290 -790);
DISPLAY INVISIBLE (-6290 -790);
FORCEPROP 2 LAST CDS_LIB pure_quanta_power
J 0
(-6300 -850);
DISPLAY INVISIBLE (-6300 -850);
FORCEPROP 1 LAST HDL_POWER GND
J 1
(-6275 -925);
DISPLAY 0.872340 (-6275 -925);
PAINT GREEN (-6275 -925);
DISPLAY INVISIBLE (-6275 -925);
FORCEPROP 1 LAST PATH I177
J 0
(-6225 -850);
DISPLAY 0.872340 (-6225 -850);
PAINT AQUA (-6225 -850);
DISPLAY INVISIBLE (-6225 -850);
FORCEADD UNIVERSAL_GND..1
(-4950 1400);
FORCEPROP 3 LASTPIN (-4950 1450) SIG_NAME GND\g
J 0
(-4940 1460);
DISPLAY 0.659574 (-4940 1460);
PAINT MONO (-4940 1460);
DISPLAY INVISIBLE (-4940 1460);
FORCEPROP 2 LAST CDS_LIB pure_quanta_power
J 0
(-4950 1400);
DISPLAY INVISIBLE (-4950 1400);
FORCEPROP 1 LAST HDL_POWER GND
J 1
(-4925 1325);
DISPLAY 0.872340 (-4925 1325);
PAINT GREEN (-4925 1325);
DISPLAY INVISIBLE (-4925 1325);
FORCEPROP 1 LAST PATH I178
J 0
(-4875 1400);
DISPLAY 0.872340 (-4875 1400);
PAINT AQUA (-4875 1400);
DISPLAY INVISIBLE (-4875 1400);
FORCEADD OFFPAGE..2
(-3425 1900);
FORCEPROP 2 LAST $XR0 122 
J 0
(-3236 1900);
DISPLAY 0.638298 (-3236 1900);
PAINT MONO (-3236 1900);
FORCEPROP 2 LAST CDS_LIB standard
J 0
(-3425 1900);
DISPLAY INVISIBLE (-3425 1900);
FORCEPROP 1 LAST OFFPAGE TRUE
J 0
(-3100 1775);
DISPLAY 0.872340 (-3100 1775);
PAINT AQUA (-3100 1775);
DISPLAY INVISIBLE (-3100 1775);
FORCEPROP 1 LAST COMMENT_BODY TRUE
J 0
(-3470 1805);
DISPLAY 0.872340 (-3470 1805);
PAINT GREEN (-3470 1805);
DISPLAY INVISIBLE (-3470 1805);
FORCEPROP 2 LAST PATH I179
J 0
(-3225 1950);
DISPLAY 1.021277 (-3225 1950);
DISPLAY INVISIBLE (-3225 1950);
FORCEADD OFFPAGE..4
R 2
(-7800 3075);
FORCEPROP 2 LAST $XR0 81 
J 0
(-8021 3075);
DISPLAY 0.638298 (-8021 3075);
PAINT MONO (-8021 3075);
FORCEPROP 2 LAST CDS_LIB standard
J 0
(-7800 3075);
DISPLAY INVISIBLE (-7800 3075);
FORCEPROP 1 LAST OFFPAGE TRUE
J 2
(-8125 2950);
DISPLAY 0.872340 (-8125 2950);
PAINT GREEN (-8125 2950);
DISPLAY INVISIBLE (-8125 2950);
FORCEPROP 1 LAST COMMENT_BODY TRUE
J 2
(-7775 2975);
DISPLAY 0.872340 (-7775 2975);
PAINT GREEN (-7775 2975);
DISPLAY INVISIBLE (-7775 2975);
FORCEPROP 2 LAST PATH I18
J 0
(-8050 3125);
DISPLAY 1.021277 (-8050 3125);
DISPLAY INVISIBLE (-8050 3125);
FORCEADD Q_RES..1
(-4625 1900);
FORCEPROP 1 LAST LOCATION R3469
J 0
(-4850 1900);
DISPLAY 0.638298 (-4850 1900);
FORCEPROP 0 LAST $SEC 1
J 0
(-4675 2000);
DISPLAY 0.680851 (-4675 2000);
PAINT MONO (-4675 2000);
DISPLAY INVISIBLE (-4675 2000);
FORCEPROP 0 LAST CDS_SEC 1
J 0
(-4675 2000);
DISPLAY 1.021277 (-4675 2000);
DISPLAY INVISIBLE (-4675 2000);
FORCEPROP 1 LASTPIN (-4725 1900) $PN 1
J 0
(-4713 1912);
DISPLAY 0.787234 (-4713 1912);
PAINT MONO (-4713 1912);
FORCEPROP 1 LASTPIN (-4525 1900) $PN 2
J 0
(-4563 1912);
DISPLAY 0.787234 (-4563 1912);
PAINT MONO (-4563 1912);
FORCEPROP 1 LAST MATERIAL CHIP
J 0
(-4600 1850);
DISPLAY 0.723404 (-4600 1850);
FORCEPROP 1 LAST PACK_TYPE 0402LF
J 0
(-4800 1850);
DISPLAY 0.723404 (-4800 1850);
FORCEPROP 1 LAST VALUE 49.9
J 2
(-4375 1900);
DISPLAY 0.723404 (-4375 1900);
FORCEPROP 2 LAST CDS_LIB pure_quanta
J 0
(-4625 1900);
DISPLAY INVISIBLE (-4625 1900);
FORCEPROP 1 LAST TOLERANCE 1%
J 0
(-4150 1900);
DISPLAY 0.723404 (-4150 1900);
PAINT SKYBLUE (-4150 1900);
DISPLAY INVISIBLE (-4150 1900);
FORCEPROP 1 LAST WATTAGE 1/16W
J 2
(-4225 1850);
DISPLAY 0.723404 (-4225 1850);
PAINT SKYBLUE (-4225 1850);
DISPLAY INVISIBLE (-4225 1850);
FORCEPROP 1 LAST PATH I180
J 0
(-4675 2050);
DISPLAY 0.978723 (-4675 2050);
PAINT WHITE (-4675 2050);
DISPLAY INVISIBLE (-4675 2050);
FORCEPROP 1 LAST PART_NUMBER CS04992FB07
J 0
(-5025 1800);
DISPLAY 0.723404 (-5025 1800);
PAINT WHITE (-5025 1800);
DISPLAY INVISIBLE (-5025 1800);
FORCEADD Q_RES..2
(-4950 1625);
FORCEPROP 1 LAST LOCATION R3467
J 0
(-4905 1750);
DISPLAY 0.978723 (-4905 1750);
FORCEPROP 0 LAST $SEC 1
J 0
(-4900 1800);
DISPLAY 0.680851 (-4900 1800);
PAINT MONO (-4900 1800);
DISPLAY INVISIBLE (-4900 1800);
FORCEPROP 0 LAST CDS_SEC 1
J 0
(-4900 1800);
DISPLAY 1.021277 (-4900 1800);
DISPLAY INVISIBLE (-4900 1800);
FORCEPROP 1 LASTPIN (-4950 1725) $PN 1
J 0
(-4945 1687);
DISPLAY 0.787234 (-4945 1687);
PAINT MONO (-4945 1687);
FORCEPROP 1 LASTPIN (-4950 1525) $PN 2
J 0
(-4945 1535);
DISPLAY 0.787234 (-4945 1535);
PAINT MONO (-4945 1535);
FORCEPROP 1 LAST MATERIAL CHIP
J 0
(-4910 1550);
DISPLAY 0.510638 (-4910 1550);
FORCEPROP 1 LAST VALUE 10K
J 0
(-4905 1700);
DISPLAY 0.510638 (-4905 1700);
FORCEPROP 1 LAST TOLERANCE 1%
J 0
(-4905 1650);
DISPLAY 0.510638 (-4905 1650);
FORCEPROP 1 LAST WATTAGE 1/16W
J 0
(-4910 1600);
DISPLAY 0.510638 (-4910 1600);
FORCEPROP 1 LAST PACK_TYPE 0402LF
J 0
(-4910 1450);
DISPLAY 0.510638 (-4910 1450);
FORCEPROP 2 LAST CDS_LIB pure_quanta
J 0
(-4950 1625);
DISPLAY INVISIBLE (-4950 1625);
FORCEPROP 1 LAST PATH I181
J 0
(-4900 1800);
DISPLAY 0.978723 (-4900 1800);
PAINT WHITE (-4900 1800);
DISPLAY INVISIBLE (-4900 1800);
FORCEPROP 1 LAST PART_NUMBER CS31002FB08
J 0
(-4910 1500);
DISPLAY 0.510638 (-4910 1500);
DISPLAY INVISIBLE (-4910 1500);
FORCEADD OFFPAGE..2
(-3425 100);
FORCEPROP 2 LAST $XR0 122 
J 0
(-3236 100);
DISPLAY 0.638298 (-3236 100);
PAINT MONO (-3236 100);
FORCEPROP 2 LAST CDS_LIB standard
J 0
(-3425 100);
DISPLAY INVISIBLE (-3425 100);
FORCEPROP 1 LAST OFFPAGE TRUE
J 0
(-3100 -25);
DISPLAY 0.872340 (-3100 -25);
PAINT AQUA (-3100 -25);
DISPLAY INVISIBLE (-3100 -25);
FORCEPROP 1 LAST COMMENT_BODY TRUE
J 0
(-3470 5);
DISPLAY 0.872340 (-3470 5);
PAINT GREEN (-3470 5);
DISPLAY INVISIBLE (-3470 5);
FORCEPROP 2 LAST PATH I182
J 0
(-3225 150);
DISPLAY 1.021277 (-3225 150);
DISPLAY INVISIBLE (-3225 150);
FORCEADD Q_RES..1
(-4650 100);
FORCEPROP 1 LAST LOCATION R3468
J 0
(-4875 100);
DISPLAY 0.638298 (-4875 100);
FORCEPROP 0 LAST $SEC 1
J 0
(-4700 200);
DISPLAY 0.680851 (-4700 200);
PAINT MONO (-4700 200);
DISPLAY INVISIBLE (-4700 200);
FORCEPROP 0 LAST CDS_SEC 1
J 0
(-4700 200);
DISPLAY 1.021277 (-4700 200);
DISPLAY INVISIBLE (-4700 200);
FORCEPROP 1 LASTPIN (-4750 100) $PN 1
J 0
(-4738 112);
DISPLAY 0.787234 (-4738 112);
PAINT MONO (-4738 112);
FORCEPROP 1 LASTPIN (-4550 100) $PN 2
J 0
(-4588 112);
DISPLAY 0.787234 (-4588 112);
PAINT MONO (-4588 112);
FORCEPROP 1 LAST VALUE 49.9
J 2
(-4400 100);
DISPLAY 0.723404 (-4400 100);
FORCEPROP 1 LAST MATERIAL CHIP
J 0
(-4625 50);
DISPLAY 0.723404 (-4625 50);
FORCEPROP 1 LAST PACK_TYPE 0402LF
J 0
(-4825 50);
DISPLAY 0.723404 (-4825 50);
FORCEPROP 1 LAST WATTAGE 1/16W
J 2
(-4250 50);
DISPLAY 0.723404 (-4250 50);
PAINT SKYBLUE (-4250 50);
DISPLAY INVISIBLE (-4250 50);
FORCEPROP 1 LAST TOLERANCE 1%
J 0
(-4175 100);
DISPLAY 0.723404 (-4175 100);
PAINT SKYBLUE (-4175 100);
DISPLAY INVISIBLE (-4175 100);
FORCEPROP 2 LAST CDS_LIB pure_quanta
J 0
(-4650 100);
DISPLAY INVISIBLE (-4650 100);
FORCEPROP 1 LAST PATH I183
J 0
(-4700 250);
DISPLAY 0.978723 (-4700 250);
PAINT WHITE (-4700 250);
DISPLAY INVISIBLE (-4700 250);
FORCEPROP 1 LAST PART_NUMBER CS04992FB07
J 0
(-5050 0);
DISPLAY 0.723404 (-5050 0);
PAINT WHITE (-5050 0);
DISPLAY INVISIBLE (-5050 0);
FORCEADD Q_RES..2
(-4975 -175);
FORCEPROP 1 LAST LOCATION R3466
J 0
(-4930 -50);
DISPLAY 0.978723 (-4930 -50);
FORCEPROP 0 LAST $SEC 1
J 0
(-4925 0);
DISPLAY 0.680851 (-4925 0);
PAINT MONO (-4925 0);
DISPLAY INVISIBLE (-4925 0);
FORCEPROP 0 LAST CDS_SEC 1
J 0
(-4925 0);
DISPLAY 1.021277 (-4925 0);
DISPLAY INVISIBLE (-4925 0);
FORCEPROP 1 LASTPIN (-4975 -75) $PN 1
J 0
(-4970 -113);
DISPLAY 0.787234 (-4970 -113);
PAINT MONO (-4970 -113);
FORCEPROP 1 LASTPIN (-4975 -275) $PN 2
J 0
(-4970 -265);
DISPLAY 0.787234 (-4970 -265);
PAINT MONO (-4970 -265);
FORCEPROP 1 LAST TOLERANCE 1%
J 0
(-4930 -150);
DISPLAY 0.510638 (-4930 -150);
FORCEPROP 1 LAST WATTAGE 1/16W
J 0
(-4935 -200);
DISPLAY 0.510638 (-4935 -200);
FORCEPROP 1 LAST MATERIAL CHIP
J 0
(-4935 -250);
DISPLAY 0.510638 (-4935 -250);
FORCEPROP 1 LAST PACK_TYPE 0402LF
J 0
(-4935 -350);
DISPLAY 0.510638 (-4935 -350);
FORCEPROP 1 LAST VALUE 10K
J 0
(-4930 -100);
DISPLAY 0.510638 (-4930 -100);
FORCEPROP 2 LAST CDS_LIB pure_quanta
J 0
(-4975 -175);
DISPLAY INVISIBLE (-4975 -175);
FORCEPROP 1 LAST PATH I184
J 0
(-4925 0);
DISPLAY 0.978723 (-4925 0);
PAINT WHITE (-4925 0);
DISPLAY INVISIBLE (-4925 0);
FORCEPROP 1 LAST PART_NUMBER CS31002FB08
J 0
(-4935 -300);
DISPLAY 0.510638 (-4935 -300);
DISPLAY INVISIBLE (-4935 -300);
FORCEADD UNIVERSAL_GND..1
(-4975 -400);
FORCEPROP 3 LASTPIN (-4975 -350) SIG_NAME GND\g
J 0
(-4965 -340);
DISPLAY 0.659574 (-4965 -340);
PAINT MONO (-4965 -340);
DISPLAY INVISIBLE (-4965 -340);
FORCEPROP 2 LAST CDS_LIB pure_quanta_power
J 0
(-4975 -400);
DISPLAY INVISIBLE (-4975 -400);
FORCEPROP 1 LAST HDL_POWER GND
J 1
(-4950 -475);
DISPLAY 0.872340 (-4950 -475);
PAINT GREEN (-4950 -475);
DISPLAY INVISIBLE (-4950 -475);
FORCEPROP 1 LAST PATH I185
J 0
(-4900 -400);
DISPLAY 0.872340 (-4900 -400);
PAINT AQUA (-4900 -400);
DISPLAY INVISIBLE (-4900 -400);
FORCEADD UNIVERSAL_POWER..1
(-7800 125);
FORCEPROP 3 LASTPIN (-7800 75) SIG_NAME P3V3_AUX\g
J 0
(-7790 85);
DISPLAY 0.659574 (-7790 85);
PAINT MONO (-7790 85);
DISPLAY INVISIBLE (-7790 85);
FORCEPROP 1 LAST HDL_POWER P3V3_AUX
J 1
(-7800 175);
DISPLAY 0.872340 (-7800 175);
PAINT GREEN (-7800 175);
FORCEPROP 2 LAST CDS_LIB pure_quanta_power
J 0
(-7800 125);
PAINT MONO (-7800 125);
DISPLAY INVISIBLE (-7800 125);
FORCEPROP 1 LAST PATH I186
J 0
(-7750 150);
DISPLAY 0.872340 (-7750 150);
PAINT AQUA (-7750 150);
DISPLAY INVISIBLE (-7750 150);
FORCEADD Q_RES..2
(-7800 -125);
FORCEPROP 1 LAST LOCATION R2910
J 0
(-7755 0);
DISPLAY 0.978723 (-7755 0);
FORCEPROP 0 LAST $SEC 1
J 0
(-7750 50);
DISPLAY 0.680851 (-7750 50);
PAINT MONO (-7750 50);
DISPLAY INVISIBLE (-7750 50);
FORCEPROP 0 LAST CDS_SEC 1
J 0
(-7750 50);
DISPLAY 1.021277 (-7750 50);
DISPLAY INVISIBLE (-7750 50);
FORCEPROP 1 LASTPIN (-7800 -25) $PN 1
J 0
(-7795 -63);
DISPLAY 0.787234 (-7795 -63);
PAINT MONO (-7795 -63);
FORCEPROP 1 LASTPIN (-7800 -225) $PN 2
J 0
(-7795 -215);
DISPLAY 0.787234 (-7795 -215);
PAINT MONO (-7795 -215);
FORCEPROP 1 LAST TOLERANCE 1%
J 0
(-7755 -100);
DISPLAY 0.510638 (-7755 -100);
FORCEPROP 1 LAST WATTAGE 1/16W
J 0
(-7760 -150);
DISPLAY 0.510638 (-7760 -150);
FORCEPROP 1 LAST MATERIAL EMPTY
J 0
(-7760 -200);
DISPLAY 0.510638 (-7760 -200);
PAINT RED (-7760 -200);
FORCEPROP 1 LAST VALUE 100K
J 0
(-7755 -50);
DISPLAY 0.510638 (-7755 -50);
FORCEPROP 1 LAST PACK_TYPE 0402LF
J 0
(-7760 -300);
DISPLAY 0.510638 (-7760 -300);
FORCEPROP 2 LAST CDS_LIB pure_quanta
J 0
(-7800 -125);
DISPLAY INVISIBLE (-7800 -125);
FORCEPROP 1 LAST PATH I187
J 0
(-7750 50);
DISPLAY 0.978723 (-7750 50);
PAINT WHITE (-7750 50);
DISPLAY INVISIBLE (-7750 50);
FORCEPROP 1 LAST PART_NUMBER CS41002FB09
J 0
(-7760 -250);
DISPLAY 0.510638 (-7760 -250);
DISPLAY INVISIBLE (-7760 -250);
FORCEADD Q_RES..2
(-7775 -600);
FORCEPROP 1 LAST LOCATION R2918
J 0
(-7730 -475);
DISPLAY 0.638298 (-7730 -475);
FORCEPROP 2 LAST $SEC 1
J 0
(-7725 -375);
DISPLAY 0.680851 (-7725 -375);
PAINT MONO (-7725 -375);
DISPLAY INVISIBLE (-7725 -375);
FORCEPROP 2 LAST CDS_SEC 1
J 0
(-7725 -375);
DISPLAY 1.021277 (-7725 -375);
DISPLAY INVISIBLE (-7725 -375);
FORCEPROP 1 LASTPIN (-7775 -500) $PN 1
J 0
(-7770 -538);
DISPLAY 0.787234 (-7770 -538);
FORCEPROP 1 LASTPIN (-7775 -700) $PN 2
J 0
(-7770 -690);
DISPLAY 0.787234 (-7770 -690);
FORCEPROP 1 LAST PACK_TYPE 0402LF
J 0
(-7735 -725);
DISPLAY 0.638298 (-7735 -725);
FORCEPROP 1 LAST TOLERANCE 5%
J 0
(-7730 -575);
DISPLAY 0.638298 (-7730 -575);
FORCEPROP 1 LAST MATERIAL CHIP
J 0
(-7735 -675);
DISPLAY 0.638298 (-7735 -675);
FORCEPROP 1 LAST VALUE 4.7K
J 0
(-7730 -525);
DISPLAY 0.638298 (-7730 -525);
FORCEPROP 1 LAST WATTAGE 1/16W
J 0
(-7735 -625);
DISPLAY 0.638298 (-7735 -625);
FORCEPROP 2 LAST CDS_LIB pure_quanta
J 0
(-7775 -600);
PAINT MONO (-7775 -600);
DISPLAY INVISIBLE (-7775 -600);
FORCEPROP 1 LAST PATH I188
J 0
(-7725 -425);
DISPLAY 0.978723 (-7725 -425);
PAINT WHITE (-7725 -425);
DISPLAY INVISIBLE (-7725 -425);
FORCEPROP 1 LAST PART_NUMBER CS24702JB10
J 0
(-7735 -775);
DISPLAY 0.638298 (-7735 -775);
DISPLAY INVISIBLE (-7735 -775);
FORCEADD UNIVERSAL_GND..1
(-7775 -775);
FORCEPROP 3 LASTPIN (-7775 -725) SIG_NAME GND\g
J 0
(-7765 -715);
DISPLAY 0.659574 (-7765 -715);
PAINT MONO (-7765 -715);
DISPLAY INVISIBLE (-7765 -715);
FORCEPROP 2 LAST CDS_LIB pure_quanta_power
J 0
(-7775 -775);
DISPLAY INVISIBLE (-7775 -775);
FORCEPROP 1 LAST HDL_POWER GND
J 1
(-7750 -850);
DISPLAY 0.872340 (-7750 -850);
PAINT GREEN (-7750 -850);
DISPLAY INVISIBLE (-7750 -850);
FORCEPROP 1 LAST PATH I189
J 0
(-7700 -775);
DISPLAY 0.872340 (-7700 -775);
PAINT AQUA (-7700 -775);
DISPLAY INVISIBLE (-7700 -775);
FORCEADD OFFPAGE..4
R 2
(-8000 -400);
FORCEPROP 2 LAST $XR0 81 
J 0
(-8251 -400);
DISPLAY 0.638298 (-8251 -400);
PAINT MONO (-8251 -400);
FORCEPROP 2 LAST CDS_LIB standard
J 0
(-8000 -400);
DISPLAY INVISIBLE (-8000 -400);
FORCEPROP 1 LAST OFFPAGE TRUE
J 2
(-8325 -525);
DISPLAY 0.872340 (-8325 -525);
PAINT GREEN (-8325 -525);
DISPLAY INVISIBLE (-8325 -525);
FORCEPROP 1 LAST COMMENT_BODY TRUE
J 2
(-7975 -500);
DISPLAY 0.872340 (-7975 -500);
PAINT GREEN (-7975 -500);
DISPLAY INVISIBLE (-7975 -500);
FORCEPROP 2 LAST PATH I190
J 0
(-8250 -350);
DISPLAY 1.021277 (-8250 -350);
DISPLAY INVISIBLE (-8250 -350);
FORCEADD UNIVERSAL_POWER..1
(-4150 -50);
FORCEPROP 3 LASTPIN (-4150 -100) SIG_NAME P3V3_AUX\g
J 0
(-4140 -90);
DISPLAY 0.659574 (-4140 -90);
PAINT MONO (-4140 -90);
DISPLAY INVISIBLE (-4140 -90);
FORCEPROP 1 LAST HDL_POWER P3V3_AUX
J 1
(-4150 0);
DISPLAY 0.872340 (-4150 0);
PAINT GREEN (-4150 0);
FORCEPROP 2 LAST CDS_LIB pure_quanta_power
J 0
(-4150 -50);
PAINT MONO (-4150 -50);
DISPLAY INVISIBLE (-4150 -50);
FORCEPROP 1 LAST PATH I191
J 0
(-4100 -25);
DISPLAY 0.872340 (-4100 -25);
PAINT AQUA (-4100 -25);
DISPLAY INVISIBLE (-4100 -25);
FORCEADD Q_RES..2
(-4150 -300);
FORCEPROP 1 LAST LOCATION R2914
J 0
(-4105 -175);
DISPLAY 0.638298 (-4105 -175);
FORCEPROP 2 LAST $SEC 1
J 0
(-4100 -75);
DISPLAY 0.680851 (-4100 -75);
PAINT MONO (-4100 -75);
DISPLAY INVISIBLE (-4100 -75);
FORCEPROP 2 LAST CDS_SEC 1
J 0
(-4100 -75);
DISPLAY 1.021277 (-4100 -75);
DISPLAY INVISIBLE (-4100 -75);
FORCEPROP 1 LASTPIN (-4150 -200) $PN 1
J 0
(-4145 -238);
DISPLAY 0.787234 (-4145 -238);
FORCEPROP 1 LASTPIN (-4150 -400) $PN 2
J 0
(-4145 -390);
DISPLAY 0.787234 (-4145 -390);
FORCEPROP 1 LAST TOLERANCE 5%
J 0
(-4105 -275);
DISPLAY 0.638298 (-4105 -275);
FORCEPROP 1 LAST MATERIAL EMPTY
J 0
(-4110 -375);
DISPLAY 0.638298 (-4110 -375);
PAINT RED (-4110 -375);
FORCEPROP 1 LAST PACK_TYPE 0402LF
J 0
(-4110 -425);
DISPLAY 0.638298 (-4110 -425);
FORCEPROP 1 LAST VALUE 4.7K
J 0
(-4105 -225);
DISPLAY 0.638298 (-4105 -225);
FORCEPROP 1 LAST WATTAGE 1/16W
J 0
(-4110 -325);
DISPLAY 0.638298 (-4110 -325);
FORCEPROP 2 LAST CDS_LIB pure_quanta
J 0
(-4150 -300);
PAINT MONO (-4150 -300);
DISPLAY INVISIBLE (-4150 -300);
FORCEPROP 1 LAST PATH I192
J 0
(-4100 -125);
DISPLAY 0.978723 (-4100 -125);
PAINT WHITE (-4100 -125);
DISPLAY INVISIBLE (-4100 -125);
FORCEPROP 1 LAST PART_NUMBER CS24702JB10
J 0
(-4110 -475);
DISPLAY 0.638298 (-4110 -475);
DISPLAY INVISIBLE (-4110 -475);
FORCEADD Q_RES..1
(-3925 -525);
FORCEPROP 1 LAST LOCATION R3515
J 0
(-4050 -525);
DISPLAY 0.638298 (-4050 -525);
FORCEPROP 0 LAST $SEC 1
J 0
(-3675 -475);
DISPLAY 0.680851 (-3675 -475);
PAINT MONO (-3675 -475);
DISPLAY INVISIBLE (-3675 -475);
FORCEPROP 0 LAST CDS_SEC 1
J 0
(-3675 -475);
DISPLAY 1.021277 (-3675 -475);
DISPLAY INVISIBLE (-3675 -475);
FORCEPROP 1 LASTPIN (-4025 -525) $PN 1
J 0
(-4013 -513);
DISPLAY 0.787234 (-4013 -513);
PAINT MONO (-4013 -513);
FORCEPROP 1 LASTPIN (-3825 -525) $PN 2
J 0
(-3863 -513);
DISPLAY 0.787234 (-3863 -513);
PAINT MONO (-3863 -513);
FORCEPROP 1 LAST MATERIAL CHIP
J 0
(-3900 -575);
DISPLAY 0.723404 (-3900 -575);
FORCEPROP 1 LAST PACK_TYPE 0402LF
J 0
(-4100 -575);
DISPLAY 0.723404 (-4100 -575);
FORCEPROP 1 LAST VALUE 49.9
J 2
(-3675 -525);
DISPLAY 0.723404 (-3675 -525);
FORCEPROP 1 LAST TOLERANCE 1%
J 0
(-3450 -525);
DISPLAY 0.723404 (-3450 -525);
PAINT SKYBLUE (-3450 -525);
DISPLAY INVISIBLE (-3450 -525);
FORCEPROP 1 LAST WATTAGE 1/16W
J 2
(-3525 -575);
DISPLAY 0.723404 (-3525 -575);
PAINT SKYBLUE (-3525 -575);
DISPLAY INVISIBLE (-3525 -575);
FORCEPROP 2 LAST CDS_LIB pure_quanta
J 0
(-3925 -525);
DISPLAY INVISIBLE (-3925 -525);
FORCEPROP 1 LAST PATH I193
J 0
(-3975 -375);
DISPLAY 0.978723 (-3975 -375);
PAINT WHITE (-3975 -375);
DISPLAY INVISIBLE (-3975 -375);
FORCEPROP 1 LAST PART_NUMBER CS04992FB07
J 0
(-4325 -625);
DISPLAY 0.723404 (-4325 -625);
PAINT WHITE (-4325 -625);
DISPLAY INVISIBLE (-4325 -625);
FORCEADD OFFPAGE..2
(-2875 -525);
FORCEPROP 2 LAST $XR0 115 
J 0
(-2686 -525);
DISPLAY 0.638298 (-2686 -525);
PAINT MONO (-2686 -525);
FORCEPROP 2 LAST CDS_LIB standard
J 0
(-2875 -525);
DISPLAY INVISIBLE (-2875 -525);
FORCEPROP 1 LAST OFFPAGE TRUE
J 0
(-2550 -650);
DISPLAY 0.872340 (-2550 -650);
PAINT AQUA (-2550 -650);
DISPLAY INVISIBLE (-2550 -650);
FORCEPROP 1 LAST COMMENT_BODY TRUE
J 0
(-2920 -620);
DISPLAY 0.872340 (-2920 -620);
PAINT GREEN (-2920 -620);
DISPLAY INVISIBLE (-2920 -620);
FORCEPROP 2 LAST PATH I194
J 0
(-2675 -475);
DISPLAY 1.021277 (-2675 -475);
DISPLAY INVISIBLE (-2675 -475);
FORCEADD Q_RES..2
(-4125 -800);
FORCEPROP 1 LAST LOCATION R2932
J 0
(-4080 -675);
DISPLAY 0.978723 (-4080 -675);
FORCEPROP 0 LAST $SEC 1
J 0
(-4075 -625);
DISPLAY 0.680851 (-4075 -625);
PAINT MONO (-4075 -625);
DISPLAY INVISIBLE (-4075 -625);
FORCEPROP 0 LAST CDS_SEC 1
J 0
(-4075 -625);
DISPLAY 1.021277 (-4075 -625);
DISPLAY INVISIBLE (-4075 -625);
FORCEPROP 1 LASTPIN (-4125 -700) $PN 1
J 0
(-4120 -738);
DISPLAY 0.787234 (-4120 -738);
PAINT MONO (-4120 -738);
FORCEPROP 1 LASTPIN (-4125 -900) $PN 2
J 0
(-4120 -890);
DISPLAY 0.787234 (-4120 -890);
PAINT MONO (-4120 -890);
FORCEPROP 1 LAST PACK_TYPE 0402LF
J 0
(-4085 -925);
DISPLAY 0.638298 (-4085 -925);
FORCEPROP 1 LAST WATTAGE 1/16W
J 0
(-4085 -825);
DISPLAY 0.638298 (-4085 -825);
FORCEPROP 1 LAST MATERIAL CHIP
J 0
(-4085 -875);
DISPLAY 0.638298 (-4085 -875);
FORCEPROP 1 LAST TOLERANCE 5%
J 0
(-4080 -775);
DISPLAY 0.638298 (-4080 -775);
FORCEPROP 1 LAST VALUE 4.7K
J 0
(-4080 -725);
DISPLAY 0.638298 (-4080 -725);
FORCEPROP 2 LAST CDS_LIB pure_quanta
J 0
(-4125 -800);
DISPLAY INVISIBLE (-4125 -800);
FORCEPROP 1 LAST PATH I195
J 0
(-4075 -625);
DISPLAY 0.978723 (-4075 -625);
PAINT WHITE (-4075 -625);
DISPLAY INVISIBLE (-4075 -625);
FORCEPROP 1 LAST PART_NUMBER CS24702JB10
J 0
(-4085 -975);
DISPLAY 0.638298 (-4085 -975);
DISPLAY INVISIBLE (-4085 -975);
FORCEADD UNIVERSAL_GND..1
(-4125 -1025);
FORCEPROP 3 LASTPIN (-4125 -975) SIG_NAME GND\g
J 0
(-4115 -965);
DISPLAY 0.659574 (-4115 -965);
PAINT MONO (-4115 -965);
DISPLAY INVISIBLE (-4115 -965);
FORCEPROP 2 LAST CDS_LIB pure_quanta_power
J 0
(-4125 -1025);
DISPLAY INVISIBLE (-4125 -1025);
FORCEPROP 1 LAST HDL_POWER GND
J 1
(-4100 -1100);
DISPLAY 0.872340 (-4100 -1100);
PAINT GREEN (-4100 -1100);
DISPLAY INVISIBLE (-4100 -1100);
FORCEPROP 1 LAST PATH I196
J 0
(-4050 -1025);
DISPLAY 0.872340 (-4050 -1025);
PAINT AQUA (-4050 -1025);
DISPLAY INVISIBLE (-4050 -1025);
FORCEADD OFFPAGE..4
R 2
(-8300 575);
FORCEPROP 2 LAST $XR0 85 
J 0
(-8521 575);
DISPLAY 0.638298 (-8521 575);
PAINT MONO (-8521 575);
FORCEPROP 2 LAST CDS_LIB standard
J 0
(-8300 575);
DISPLAY INVISIBLE (-8300 575);
FORCEPROP 1 LAST OFFPAGE TRUE
J 2
(-8625 450);
DISPLAY 0.872340 (-8625 450);
PAINT GREEN (-8625 450);
DISPLAY INVISIBLE (-8625 450);
FORCEPROP 1 LAST COMMENT_BODY TRUE
J 2
(-8275 475);
DISPLAY 0.872340 (-8275 475);
PAINT GREEN (-8275 475);
DISPLAY INVISIBLE (-8275 475);
FORCEPROP 2 LAST PATH I197
J 0
(-8500 625);
DISPLAY 0.680851 (-8500 625);
DISPLAY INVISIBLE (-8500 625);
FORCEADD OFFPAGE..4
R 2
(-8300 1450);
FORCEPROP 2 LAST $XR0 85 
J 0
(-8521 1450);
DISPLAY 0.638298 (-8521 1450);
PAINT MONO (-8521 1450);
FORCEPROP 2 LAST CDS_LIB standard
J 0
(-8300 1450);
DISPLAY INVISIBLE (-8300 1450);
FORCEPROP 1 LAST OFFPAGE TRUE
J 2
(-8625 1325);
DISPLAY 0.872340 (-8625 1325);
PAINT GREEN (-8625 1325);
DISPLAY INVISIBLE (-8625 1325);
FORCEPROP 1 LAST COMMENT_BODY TRUE
J 2
(-8275 1350);
DISPLAY 0.872340 (-8275 1350);
PAINT GREEN (-8275 1350);
DISPLAY INVISIBLE (-8275 1350);
FORCEPROP 2 LAST PATH I198
J 0
(-8250 1525);
DISPLAY 0.680851 (-8250 1525);
DISPLAY INVISIBLE (-8250 1525);
FORCEADD UNIVERSAL_POWER..1
(-7600 3525);
FORCEPROP 3 LASTPIN (-7600 3475) SIG_NAME P3V3_AUX\g
J 0
(-7590 3485);
DISPLAY 0.659574 (-7590 3485);
PAINT MONO (-7590 3485);
DISPLAY INVISIBLE (-7590 3485);
FORCEPROP 1 LAST HDL_POWER P3V3_AUX
J 1
(-7600 3575);
DISPLAY 0.872340 (-7600 3575);
PAINT GREEN (-7600 3575);
FORCEPROP 2 LAST CDS_LIB pure_quanta_power
J 0
(-7600 3525);
PAINT MONO (-7600 3525);
DISPLAY INVISIBLE (-7600 3525);
FORCEPROP 1 LAST PATH I20
J 0
(-7550 3550);
DISPLAY 0.872340 (-7550 3550);
PAINT AQUA (-7550 3550);
DISPLAY INVISIBLE (-7550 3550);
FORCEADD 74LVC2G17GW..1
(-6125 3575);
FORCEPROP 1 LAST LOCATION U253
J 0
(-5898 3335);
DISPLAY 0.723404 (-5898 3335);
PAINT GREEN (-5898 3335);
FORCEPROP 0 LAST $SEC 1
J 0
(-5875 3375);
DISPLAY 0.680851 (-5875 3375);
PAINT MONO (-5875 3375);
DISPLAY INVISIBLE (-5875 3375);
FORCEPROP 0 LAST CDS_SEC 1
J 0
(-5875 3375);
DISPLAY 1.021277 (-5875 3375);
DISPLAY INVISIBLE (-5875 3375);
FORCEPROP 0 LASTPIN (-6500 3700) $PN 1
J 2
(-6510 3710);
DISPLAY 0.680851 (-6510 3710);
PAINT MONO (-6510 3710);
FORCEPROP 0 LASTPIN (-6500 3450) $PN 3
J 2
(-6510 3460);
DISPLAY 0.680851 (-6510 3460);
PAINT MONO (-6510 3460);
FORCEPROP 0 LASTPIN (-5750 3700) $PN 6
J 0
(-5740 3710);
DISPLAY 0.680851 (-5740 3710);
PAINT MONO (-5740 3710);
FORCEPROP 0 LASTPIN (-5750 3450) $PN 4
J 0
(-5740 3460);
DISPLAY 0.680851 (-5740 3460);
PAINT MONO (-5740 3460);
FORCEPROP 0 LASTPIN (-6100 3150) $PN 2
R 1
J 2
(-6110 3140);
DISPLAY 0.680851 (-6110 3140);
PAINT MONO (-6110 3140);
FORCEPROP 0 LASTPIN (-6100 4000) $PN 5
R 1
J 0
(-6110 4010);
DISPLAY 0.680851 (-6110 4010);
PAINT MONO (-6110 4010);
FORCEPROP 2 LAST VALUE 74LVC2G17GW
J 0
(-6325 2850);
DISPLAY 1.021277 (-6325 2850);
FORCEPROP 2 LAST PART_TYPE SMLF
J 0
(-6325 2900);
DISPLAY 1.021277 (-6325 2900);
FORCEPROP 1 LAST MATERIAL IC
J 0
(-6325 2750);
DISPLAY 0.723404 (-6325 2750);
PAINT GREEN (-6325 2750);
FORCEPROP 2 LAST CDS_LIB pure_quanta
J 0
(-6125 3575);
DISPLAY INVISIBLE (-6125 3575);
FORCEPROP 1 LAST NEEDS_NO_SIZE TRUE
J 0
(-5900 3574);
DISPLAY 0.468085 (-5900 3574);
PAINT GREEN (-5900 3574);
DISPLAY INVISIBLE (-5900 3574);
FORCEPROP 1 LAST CDS_LMAN_SYM_OUTLINE -225,275,225,-275
J 0
(-6125 3575);
DISPLAY 0.468085 (-6125 3575);
PAINT GREEN (-6125 3575);
DISPLAY INVISIBLE (-6125 3575);
FORCEPROP 1 LAST PATH I26
J 0
(-5900 3300);
DISPLAY 0.723404 (-5900 3300);
PAINT GREEN (-5900 3300);
DISPLAY INVISIBLE (-5900 3300);
FORCEPROP 1 LAST PART_NUMBER AL2G0017005
J 0
(-6325 2800);
DISPLAY 0.723404 (-6325 2800);
PAINT GREEN (-6325 2800);
DISPLAY INVISIBLE (-6325 2800);
FORCEADD UNIVERSAL_GND..1
(-6100 2975);
FORCEPROP 3 LASTPIN (-6100 3025) SIG_NAME GND\g
J 0
(-6090 3035);
DISPLAY 0.659574 (-6090 3035);
PAINT MONO (-6090 3035);
DISPLAY INVISIBLE (-6090 3035);
FORCEPROP 2 LAST CDS_LIB pure_quanta_power
J 0
(-6100 2975);
DISPLAY INVISIBLE (-6100 2975);
FORCEPROP 1 LAST HDL_POWER GND
J 1
(-6075 2900);
DISPLAY 0.872340 (-6075 2900);
PAINT GREEN (-6075 2900);
DISPLAY INVISIBLE (-6075 2900);
FORCEPROP 1 LAST PATH I27
J 0
(-6025 2975);
DISPLAY 0.872340 (-6025 2975);
PAINT AQUA (-6025 2975);
DISPLAY INVISIBLE (-6025 2975);
FORCEADD UNIVERSAL_GND..1
(-5975 4275);
FORCEPROP 3 LASTPIN (-5975 4325) SIG_NAME GND\g
J 0
(-5965 4335);
DISPLAY 0.659574 (-5965 4335);
PAINT MONO (-5965 4335);
DISPLAY INVISIBLE (-5965 4335);
FORCEPROP 2 LAST CDS_LIB pure_quanta_power
J 0
(-5975 4275);
PAINT MONO (-5975 4275);
DISPLAY INVISIBLE (-5975 4275);
FORCEPROP 1 LAST HDL_POWER GND
J 1
(-5950 4200);
DISPLAY 0.872340 (-5950 4200);
PAINT GREEN (-5950 4200);
DISPLAY INVISIBLE (-5950 4200);
FORCEPROP 1 LAST PATH I28
J 0
(-5900 4275);
DISPLAY 0.872340 (-5900 4275);
PAINT AQUA (-5900 4275);
DISPLAY INVISIBLE (-5900 4275);
FORCEADD Q_CAP..1
(-5975 4500);
FORCEPROP 1 LAST LOCATION C1958
J 0
(-5925 4600);
DISPLAY 0.787234 (-5925 4600);
FORCEPROP 2 LAST $SEC 1
J 0
(-5925 4700);
DISPLAY 0.680851 (-5925 4700);
PAINT MONO (-5925 4700);
DISPLAY INVISIBLE (-5925 4700);
FORCEPROP 2 LAST CDS_SEC 1
J 0
(-5925 4700);
DISPLAY 1.021277 (-5925 4700);
DISPLAY INVISIBLE (-5925 4700);
FORCEPROP 1 LASTPIN (-5975 4600) $PN 1
J 0
(-5965 4580);
DISPLAY 0.787234 (-5965 4580);
FORCEPROP 1 LASTPIN (-5975 4400) $PN 2
J 0
(-5965 4380);
DISPLAY 0.787234 (-5965 4380);
FORCEPROP 1 LAST TOLERANCE 10%
J 0
(-5925 4450);
DISPLAY 0.510638 (-5925 4450);
FORCEPROP 1 LAST MATERIAL X7R
J 0
(-5925 4400);
DISPLAY 0.510638 (-5925 4400);
FORCEPROP 1 LAST PACK_TYPE 0402
J 0
(-5925 4300);
DISPLAY 0.510638 (-5925 4300);
FORCEPROP 1 LAST VOLTAGE 25V
J 0
(-5925 4500);
DISPLAY 0.510638 (-5925 4500);
FORCEPROP 1 LAST VALUE 0.1UF
J 0
(-5925 4550);
DISPLAY 0.510638 (-5925 4550);
FORCEPROP 2 LAST CDS_LIB pure_quanta
J 2
(-5975 4500);
PAINT MONO (-5975 4500);
DISPLAY INVISIBLE (-5975 4500);
FORCEPROP 1 LAST PATH I29
J 0
(-5925 4650);
DISPLAY 0.978723 (-5925 4650);
PAINT WHITE (-5925 4650);
DISPLAY INVISIBLE (-5925 4650);
FORCEPROP 1 LAST PART_NUMBER CH4104K1B00
J 0
(-5925 4350);
DISPLAY 0.510638 (-5925 4350);
DISPLAY INVISIBLE (-5925 4350);
FORCEADD UNIVERSAL_POWER..1
(-5975 4825);
FORCEPROP 3 LASTPIN (-5975 4775) SIG_NAME P3V3_AUX\g
J 0
(-5965 4785);
DISPLAY 0.659574 (-5965 4785);
PAINT MONO (-5965 4785);
DISPLAY INVISIBLE (-5965 4785);
FORCEPROP 1 LAST HDL_POWER P3V3_AUX
J 1
(-5975 4875);
DISPLAY 0.872340 (-5975 4875);
PAINT GREEN (-5975 4875);
FORCEPROP 2 LAST CDS_LIB pure_quanta_power
J 0
(-5975 4825);
PAINT MONO (-5975 4825);
DISPLAY INVISIBLE (-5975 4825);
FORCEPROP 1 LAST PATH I30
J 0
(-5925 4850);
DISPLAY 0.872340 (-5925 4850);
PAINT AQUA (-5925 4850);
DISPLAY INVISIBLE (-5925 4850);
FORCEADD Q_RES..1
(-4625 3000);
FORCEPROP 1 LAST LOCATION R3392
J 0
(-4850 3000);
DISPLAY 0.638298 (-4850 3000);
FORCEPROP 0 LAST $SEC 1
J 0
(-4675 3100);
DISPLAY 0.680851 (-4675 3100);
PAINT MONO (-4675 3100);
DISPLAY INVISIBLE (-4675 3100);
FORCEPROP 0 LAST CDS_SEC 1
J 0
(-4675 3100);
DISPLAY 1.021277 (-4675 3100);
DISPLAY INVISIBLE (-4675 3100);
FORCEPROP 1 LASTPIN (-4725 3000) $PN 1
J 0
(-4713 3012);
DISPLAY 0.787234 (-4713 3012);
PAINT MONO (-4713 3012);
FORCEPROP 1 LASTPIN (-4525 3000) $PN 2
J 0
(-4563 3012);
DISPLAY 0.787234 (-4563 3012);
PAINT MONO (-4563 3012);
FORCEPROP 1 LAST MATERIAL CHIP
J 0
(-4600 2950);
DISPLAY 0.723404 (-4600 2950);
FORCEPROP 1 LAST PACK_TYPE 0402LF
J 0
(-4800 2950);
DISPLAY 0.723404 (-4800 2950);
FORCEPROP 1 LAST VALUE 49.9
J 2
(-4375 3000);
DISPLAY 0.723404 (-4375 3000);
FORCEPROP 1 LAST WATTAGE 1/16W
J 2
(-4225 2950);
DISPLAY 0.723404 (-4225 2950);
PAINT SKYBLUE (-4225 2950);
DISPLAY INVISIBLE (-4225 2950);
FORCEPROP 1 LAST TOLERANCE 1%
J 0
(-4150 3000);
DISPLAY 0.723404 (-4150 3000);
PAINT SKYBLUE (-4150 3000);
DISPLAY INVISIBLE (-4150 3000);
FORCEPROP 2 LAST CDS_LIB pure_quanta
J 0
(-4625 3000);
DISPLAY INVISIBLE (-4625 3000);
FORCEPROP 1 LAST PATH I62
J 0
(-4675 3150);
DISPLAY 0.978723 (-4675 3150);
PAINT WHITE (-4675 3150);
DISPLAY INVISIBLE (-4675 3150);
FORCEPROP 1 LAST PART_NUMBER CS04992FB07
J 0
(-5025 2900);
DISPLAY 0.723404 (-5025 2900);
PAINT WHITE (-5025 2900);
DISPLAY INVISIBLE (-5025 2900);
FORCEADD OFFPAGE..2
(-3425 3000);
FORCEPROP 2 LAST $XR0 120 
J 0
(-3236 3000);
DISPLAY 0.638298 (-3236 3000);
PAINT MONO (-3236 3000);
FORCEPROP 2 LAST CDS_LIB standard
J 0
(-3425 3000);
DISPLAY INVISIBLE (-3425 3000);
FORCEPROP 1 LAST OFFPAGE TRUE
J 0
(-3100 2875);
DISPLAY 0.872340 (-3100 2875);
PAINT AQUA (-3100 2875);
DISPLAY INVISIBLE (-3100 2875);
FORCEPROP 1 LAST COMMENT_BODY TRUE
J 0
(-3470 2905);
DISPLAY 0.872340 (-3470 2905);
PAINT GREEN (-3470 2905);
DISPLAY INVISIBLE (-3470 2905);
FORCEPROP 2 LAST PATH I67
J 0
(-3225 3050);
DISPLAY 1.021277 (-3225 3050);
DISPLAY INVISIBLE (-3225 3050);
FORCEADD Q_RES..2
(-7575 2875);
FORCEPROP 1 LAST LOCATION R3452
J 0
(-7530 3000);
DISPLAY 0.978723 (-7530 3000);
FORCEPROP 0 LAST $SEC 1
J 0
(-7525 3050);
DISPLAY 0.680851 (-7525 3050);
PAINT MONO (-7525 3050);
DISPLAY INVISIBLE (-7525 3050);
FORCEPROP 0 LAST CDS_SEC 1
J 0
(-7525 3050);
DISPLAY 1.021277 (-7525 3050);
DISPLAY INVISIBLE (-7525 3050);
FORCEPROP 1 LASTPIN (-7575 2975) $PN 1
J 0
(-7570 2937);
DISPLAY 0.787234 (-7570 2937);
PAINT MONO (-7570 2937);
FORCEPROP 1 LASTPIN (-7575 2775) $PN 2
J 0
(-7570 2785);
DISPLAY 0.787234 (-7570 2785);
PAINT MONO (-7570 2785);
FORCEPROP 1 LAST WATTAGE 1/16W
J 0
(-7535 2850);
DISPLAY 0.510638 (-7535 2850);
FORCEPROP 1 LAST VALUE 100K
J 0
(-7530 2950);
DISPLAY 0.510638 (-7530 2950);
FORCEPROP 1 LAST PACK_TYPE 0402LF
J 0
(-7535 2700);
DISPLAY 0.510638 (-7535 2700);
FORCEPROP 1 LAST MATERIAL CHIP
J 0
(-7535 2800);
DISPLAY 0.510638 (-7535 2800);
FORCEPROP 1 LAST TOLERANCE 1%
J 0
(-7530 2900);
DISPLAY 0.510638 (-7530 2900);
FORCEPROP 2 LAST CDS_LIB pure_quanta
J 0
(-7575 2875);
DISPLAY INVISIBLE (-7575 2875);
FORCEPROP 1 LAST PATH I95
J 0
(-7525 3050);
DISPLAY 0.978723 (-7525 3050);
PAINT WHITE (-7525 3050);
DISPLAY INVISIBLE (-7525 3050);
FORCEPROP 1 LAST PART_NUMBER CS41002FB09
J 0
(-7535 2750);
DISPLAY 0.510638 (-7535 2750);
DISPLAY INVISIBLE (-7535 2750);
FORCEADD DNS..2
(-4150 -325);
PAINT RED (-4150 -325);
FORCEPROP 2 LAST CDS_LIB mstr_misc
J 0
(-4150 -325);
DISPLAY INVISIBLE (-4150 -325);
FORCEPROP 1 LAST COMMENT_BODY TRUE
J 0
(-4150 -325);
DISPLAY INVISIBLE (-4150 -325);
FORCEADD DNS..2
(-7800 -150);
PAINT RED (-7800 -150);
FORCEPROP 2 LAST CDS_LIB mstr_misc
J 0
(-7800 -150);
DISPLAY INVISIBLE (-7800 -150);
FORCEPROP 1 LAST COMMENT_BODY TRUE
J 0
(-7800 -150);
DISPLAY INVISIBLE (-7800 -150);
FORCEADD DNS..2
(-5000 4400);
PAINT RED (-5000 4400);
FORCEPROP 2 LAST CDS_LIB mstr_misc
J 0
(-5000 4400);
DISPLAY INVISIBLE (-5000 4400);
FORCEPROP 1 LAST COMMENT_BODY TRUE
J 0
(-5000 4400);
DISPLAY INVISIBLE (-5000 4400);
FORCEADD DNS..2
(-4975 3200);
PAINT RED (-4975 3200);
FORCEPROP 2 LAST CDS_LIB mstr_misc
J 0
(-4975 3200);
DISPLAY INVISIBLE (-4975 3200);
FORCEPROP 1 LAST COMMENT_BODY TRUE
J 0
(-4975 3200);
DISPLAY INVISIBLE (-4975 3200);
FORCEADD QUANTA_TITLE_BLOCK_C..1
(-1200 -1575);
FORCEPROP 0 LAST CDS_CON_LAST_MODIFIED Thu Sep 14 16:12:24 2023
J 0
(-3085 -1560);
PAINT MONO (-3085 -1560);
DISPLAY INVISIBLE (-3085 -1560);
FORCEPROP 2 LAST CUSTOM_TXT_CDS <XR_PAGE_TITLE>
J 0
(-9090 3675);
DISPLAY 0.638298 (-9090 3675);
PAINT PINK (-9090 3675);
DISPLAY INVISIBLE (-9090 3675);
FORCEPROP 2 LAST CUSTOM_TXT_CDS <CON_LAST_MODIFIED>
J 0
(-3085 -1560);
DISPLAY 0.978723 (-3085 -1560);
FORCEPROP 2 LAST CUSTOM_TXT_CDS <NAME_1>
J 0
(-4375 -1400);
FORCEPROP 2 LAST CUSTOM_TXT_CDS <NAME_2>
J 0
(-4375 -1525);
FORCEPROP 2 LAST CUSTOM_TXT_CDS <Q_PROJ>
J 0
(-3582 -1473);
DISPLAY 1.212766 (-3582 -1473);
FORCEPROP 2 LAST CUSTOM_TXT_CDS <Q_NUMBER>
J 0
(-2603 -1472);
DISPLAY 1.212766 (-2603 -1472);
FORCEPROP 2 LAST CUSTOM_TXT_CDS <CON_PAGE_NUM> OF <CON_TOTAL_PAGES>
J 0
(-1646 -1557);
DISPLAY 0.978723 (-1646 -1557);
FORCEPROP 2 LAST CUSTOM_TXT_CDS <Q_REV>
J 0
(-1384 -1472);
DISPLAY 1.212766 (-1384 -1472);
FORCEPROP 1 LAST Q_TITLE EXAMAX_ISO (5/7)
J 0
(-10450 -1525);
DISPLAY 2.446809 (-10450 -1525);
PAINT GREEN (-10450 -1525);
FORCEPROP 2 LAST PAGE_BORDER TRUE
J 0
(-9090 3675);
DISPLAY 0.638298 (-9090 3675);
PAINT PINK (-9090 3675);
DISPLAY INVISIBLE (-9090 3675);
FORCEPROP 1 LAST CDS_LMAN_SYM_OUTLINE -9475,6775,100,-125
J 0
(-1200 -1575);
DISPLAY 0.468085 (-1200 -1575);
PAINT GREEN (-1200 -1575);
DISPLAY INVISIBLE (-1200 -1575);
FORCEPROP 2 LAST CDS_LIB pure_quanta
J 0
(-1200 -1575);
PAINT MONO (-1200 -1575);
DISPLAY INVISIBLE (-1200 -1575);
FORCEPROP 2 LAST CDS_XR_PAGE_TITLE CR-128 : @T6G_MB_LIB.T6G(SCH_1):PAGE128
J 0
(-9090 3675);
DISPLAY 0.638298 (-9090 3675);
PAINT PINK (-9090 3675);
DISPLAY INVISIBLE (-9090 3675);
FORCEPROP 1 LAST Q_DEPT BU9
J 1
(-4963 -1526);
DISPLAY 1.957447 (-4963 -1526);
PAINT GREEN (-4963 -1526);
DISPLAY INVISIBLE (-4963 -1526);
FORCEPROP 1 LAST COMMENT_BODY TRUE
J 0
(-1188 -1588);
DISPLAY 0.978723 (-1188 -1588);
PAINT GREEN (-1188 -1588);
DISPLAY INVISIBLE (-1188 -1588);
FORCEADD DNS..2
(-7600 4375);
PAINT RED (-7600 4375);
FORCEPROP 2 LAST CDS_LIB mstr_misc
J 0
(-7600 4375);
DISPLAY INVISIBLE (-7600 4375);
FORCEPROP 1 LAST COMMENT_BODY TRUE
J 0
(-7600 4375);
DISPLAY INVISIBLE (-7600 4375);
FORCEADD DNS..2
(-7600 3325);
PAINT RED (-7600 3325);
FORCEPROP 2 LAST CDS_LIB mstr_misc
J 0
(-7600 3325);
DISPLAY INVISIBLE (-7600 3325);
FORCEPROP 1 LAST COMMENT_BODY TRUE
J 0
(-7600 3325);
DISPLAY INVISIBLE (-7600 3325);
WIRE 16 -1 (-4975 3325)(-4975 3475);
WIRE 16 -1 (-4950 2625)(-4950 2550);
WIRE 16 -1 (-6225 1150)(-6225 1100);
WIRE 16 -1 (-4950 875)(-4950 800);
WIRE 16 -1 (-6075 2075)(-6075 2000);
WIRE 16 -1 (-7575 2675)(-7575 2775);
WIRE 16 -1 (-5000 4625)(-5000 4525);
WIRE 16 -1 (-4975 3725)(-4975 3675);
WIRE 16 -1 (-7600 4600)(-7600 4500);
WIRE 16 -1 (-7575 3775)(-7575 3825);
WIRE 16 -1 (-6175 200)(-6175 125);
WIRE 16 -1 (-6300 -700)(-6300 -800);
WIRE 16 -1 (-4950 1525)(-4950 1450);
WIRE 16 -1 (-4975 -275)(-4975 -350);
WIRE 16 -1 (-7800 75)(-7800 -25);
WIRE 16 -1 (-7775 -725)(-7775 -700);
WIRE 16 -1 (-4150 -100)(-4150 -200);
WIRE 16 -1 (-4125 -900)(-4125 -975);
WIRE 16 -1 (-7600 3475)(-7600 3450);
WIRE 16 -1 (-6100 3150)(-6100 3025);
WIRE 16 -1 (-5975 4400)(-5975 4325);
WIRE 16 -1 (-7600 4300)(-7600 4125);
WIRE 16 -1 (-7575 4125)(-7600 4125);
WIRE 16 -1 (-7600 4125)(-7800 4125);
WIRE 16 -1 (-6500 4125)(-7575 4125);
FORCEPROP 2 LAST SIG_NAME GPU_FPGA_BOOT_EN
J 0
(-7535 4135);
DISPLAY 0.808511 (-7535 4135);
WIRE 16 -1 (-7575 4025)(-7575 4125);
WIRE 16 -1 (-6500 4125)(-6500 3700);
WIRE 16 -1 (-4975 3925)(-4975 4125);
WIRE 16 -1 (-4975 4125)(-4850 4125);
WIRE 16 -1 (-5000 4125)(-4975 4125);
WIRE 16 -1 (-5000 4325)(-5000 4125);
WIRE 16 -1 (-5750 4125)(-5000 4125);
FORCEPROP 2 LAST SIG_NAME GPU_FPGA_BOOT_EN_BUF_R
J 0
(-5735 4135);
DISPLAY 0.638298 (-5735 4135);
FORCEPROP 2 LASTPROP $XRERR UNIQUE?
J 0
(-5975 4135);
DISPLAY 0.638298 (-5975 4135);
PAINT MONO (-5975 4135);
DISPLAY INVISIBLE (-5975 4135);
WIRE 16 -1 (-5750 4125)(-5750 3700);
WIRE 16 -1 (-3525 4125)(-4650 4125);
FORCEPROP 2 LAST SIG_NAME GPU_FPGA_BOOT_EN_BUF
J 0
(-4460 4135);
DISPLAY 0.808511 (-4460 4135);
WIRE 16 -1 (-7600 3250)(-7600 3075);
WIRE 16 -1 (-7575 3075)(-7600 3075);
WIRE 16 -1 (-7600 3075)(-7750 3075);
WIRE 16 -1 (-6500 3075)(-7575 3075);
FORCEPROP 2 LAST SIG_NAME GPU_BASE_STBY_EN
J 0
(-7435 3085);
DISPLAY 0.808511 (-7435 3085);
WIRE 16 -1 (-7575 3075)(-7575 2975);
WIRE 16 -1 (-6500 3450)(-6500 3075);
WIRE 16 -1 (-3475 3000)(-4525 3000);
FORCEPROP 2 LAST SIG_NAME GPU_BASE_STBY_EN_BUF
J 0
(-4310 3010);
DISPLAY 0.808511 (-4310 3010);
WIRE 16 -1 (-4950 2825)(-4950 3000);
WIRE 16 -1 (-4950 3000)(-4725 3000);
WIRE 16 -1 (-4975 3000)(-4950 3000);
WIRE 16 -1 (-4975 3125)(-4975 3000);
WIRE 16 -1 (-5750 3000)(-4975 3000);
FORCEPROP 2 LAST SIG_NAME GPU_BASE_STBY_EN_BUF_R
J 0
(-5735 3010);
DISPLAY 0.638298 (-5735 3010);
FORCEPROP 2 LASTPROP $XRERR UNIQUE?
J 0
(-5975 3010);
DISPLAY 0.638298 (-5975 3010);
PAINT MONO (-5975 3010);
DISPLAY INVISIBLE (-5975 3010);
WIRE 16 -1 (-5750 3000)(-5750 3450);
WIRE 16 -1 (-2925 -525)(-3825 -525);
FORCEPROP 2 LAST SIG_NAME FM_SWB_PWR_EN_R_BUF
J 0
(-3660 -515);
DISPLAY 0.808511 (-3660 -515);
WIRE 16 -1 (-4125 -525)(-4025 -525);
WIRE 16 -1 (-4125 -525)(-4125 -700);
WIRE 16 -1 (-4150 -525)(-4125 -525);
WIRE 16 -1 (-4150 -400)(-4150 -525);
WIRE 16 -1 (-4150 -525)(-5950 -525);
FORCEPROP 2 LAST SIG_NAME FM_SWB_PWR_EN_R1_BUF
J 0
(-4985 -515);
DISPLAY 0.808511 (-4985 -515);
FORCEPROP 2 LASTPROP $XRERR UNIQUE?
J 0
(-5225 -515);
DISPLAY 0.638298 (-5225 -515);
PAINT MONO (-5225 -515);
DISPLAY INVISIBLE (-5225 -515);
WIRE 16 -1 (-5950 -400)(-5950 -525);
WIRE 16 -1 (-6225 2000)(-6225 2375);
WIRE 16 -1 (-6075 2375)(-6225 2375);
WIRE 16 -1 (-6075 2450)(-6075 2375);
WIRE 16 -1 (-6075 2375)(-6075 2275);
WIRE 16 -1 (-6100 4000)(-6100 4700);
WIRE 16 -1 (-5975 4700)(-6100 4700);
WIRE 16 -1 (-5975 4775)(-5975 4700);
WIRE 16 -1 (-5975 4700)(-5975 4600);
WIRE 16 -1 (-7800 -225)(-7800 -400);
WIRE 16 -1 (-7800 -400)(-7775 -400);
WIRE 16 -1 (-7800 -400)(-7950 -400);
WIRE 16 -1 (-7775 -400)(-6700 -400);
FORCEPROP 2 LAST SIG_NAME FM_SWB_PWR_EN_R
J 0
(-7735 -390);
DISPLAY 0.808511 (-7735 -390);
WIRE 16 -1 (-7775 -500)(-7775 -400);
WIRE 16 -1 (-3475 1900)(-4525 1900);
FORCEPROP 2 LAST SIG_NAME RST_PERST_0_SWB_BUF_N
J 0
(-4310 1910);
DISPLAY 0.808511 (-4310 1910);
WIRE 16 -1 (-5875 1900)(-4950 1900);
FORCEPROP 2 LAST SIG_NAME RST_PERST_0_SWB_BUF_R_N
J 0
(-5860 1910);
DISPLAY 0.638298 (-5860 1910);
FORCEPROP 2 LASTPROP $XRERR UNIQUE?
J 0
(-6100 1910);
DISPLAY 0.638298 (-6100 1910);
PAINT MONO (-6100 1910);
DISPLAY INVISIBLE (-6100 1910);
WIRE 16 -1 (-5875 1900)(-5875 1700);
WIRE 16 -1 (-4950 1900)(-4725 1900);
WIRE 16 -1 (-4950 1725)(-4950 1900);
WIRE 16 -1 (-7100 575)(-8250 575);
FORCEPROP 2 LAST SIG_NAME RST_PERST_CPU0_SWB_R_N
J 0
(-8160 585);
DISPLAY 0.808511 (-8160 585);
WIRE 16 -1 (-7100 575)(-7100 -150);
WIRE 16 -1 (-7100 -150)(-6700 -150);
WIRE 16 -1 (-5875 1250)(-4950 1250);
FORCEPROP 2 LAST SIG_NAME RST_PERST_2_SWB_BUF_R_N
J 0
(-5860 1260);
DISPLAY 0.638298 (-5860 1260);
FORCEPROP 2 LASTPROP $XRERR UNIQUE?
J 0
(-6100 1260);
DISPLAY 0.638298 (-6100 1260);
PAINT MONO (-6100 1260);
DISPLAY INVISIBLE (-6100 1260);
WIRE 16 -1 (-5875 1250)(-5875 1450);
WIRE 16 -1 (-4950 1250)(-4725 1250);
WIRE 16 -1 (-4950 1075)(-4950 1250);
WIRE 16 -1 (-4975 -75)(-4975 100);
WIRE 16 -1 (-4975 100)(-4750 100);
WIRE 16 -1 (-4975 100)(-5950 100);
FORCEPROP 2 LAST SIG_NAME RST_PERST_1_SWB_BUF_R_N
J 0
(-5885 110);
DISPLAY 0.638298 (-5885 110);
FORCEPROP 2 LASTPROP $XRERR UNIQUE?
J 0
(-6125 110);
DISPLAY 0.638298 (-6125 110);
PAINT MONO (-6125 110);
DISPLAY INVISIBLE (-6125 110);
WIRE 16 -1 (-5950 -150)(-5950 100);
WIRE 16 -1 (-6300 150)(-6300 500);
WIRE 16 -1 (-6175 500)(-6300 500);
WIRE 16 -1 (-6175 575)(-6175 500);
WIRE 16 -1 (-6175 500)(-6175 400);
WIRE 16 -1 (-3475 100)(-4550 100);
FORCEPROP 2 LAST SIG_NAME RST_PERST_1_SWB_BUF_N
J 0
(-4335 110);
DISPLAY 0.808511 (-4335 110);
WIRE 16 -1 (-8250 1700)(-6625 1700);
FORCEPROP 2 LAST SIG_NAME RST_PERST_CPU1_SWB_R_N
J 0
(-8160 1710);
DISPLAY 0.808511 (-8160 1710);
WIRE 16 -1 (-3475 1250)(-4525 1250);
FORCEPROP 2 LAST SIG_NAME RST_PERST_2_SWB_BUF_N
J 0
(-4310 1260);
DISPLAY 0.808511 (-4310 1260);
WIRE 16 -1 (-8250 1450)(-6625 1450);
FORCEPROP 2 LAST SIG_NAME RST_PERST_CPU1_SWB_1_R_N
J 0
(-8160 1460);
DISPLAY 0.808511 (-8160 1460);
CIRCLE (-7625 925)(-7395 925);
PAINT YELLOW (-7625 925);
DOT 1 (-4150 -525);
DOT 1 (-4950 1900);
DOT 1 (-7800 -400);
DOT 1 (-7600 3075);
DOT 1 (-7600 4125);
DOT 1 (-6175 500);
DOT 1 (-4975 100);
DOT 1 (-4950 1250);
DOT 1 (-4950 3000);
DOT 1 (-4975 3000);
DOT 1 (-5000 4125);
DOT 1 (-5975 4700);
DOT 1 (-6075 2375);
DOT 1 (-7575 4125);
DOT 1 (-4975 4125);
DOT 1 (-7775 -400);
DOT 1 (-4125 -525);
DOT 1 (-7575 3075);
FORCENOTE
PUSH-PULL OUTPUT
(-6500 975) 0;
DISPLAY LEFT (-6500 975);
DISPLAY 1.021277 (-6500 975);
PAINT WHITE (-6500 975);
FORCENOTE
PUSH-PULL OUTPUT
(-6650 -925) 0;
DISPLAY LEFT (-6650 -925);
DISPLAY 1.021277 (-6650 -925);
PAINT WHITE (-6650 -925);
FORCENOTE
PUSH-PULL OUTPUT
(-6425 2675) 0;
DISPLAY LEFT (-6425 2675);
DISPLAY 1.021277 (-6425 2675);
PAINT WHITE (-6425 2675);
FORCENOTE
TBC
(-7700 925) 0;
DISPLAY LEFT (-7700 925);
DISPLAY 1.021277 (-7700 925);
FORCENOTE
FROM CPU1
(-2825 1250) 0;
DISPLAY LEFT (-2825 1250);
DISPLAY 1.021277 (-2825 1250);
FORCENOTE
FROM CPU1
(-2825 1900) 0;
DISPLAY LEFT (-2825 1900);
DISPLAY 1.021277 (-2825 1900);
FORCENOTE
FROM CPU0
(-2900 100) 0;
DISPLAY LEFT (-2900 100);
DISPLAY 1.021277 (-2900 100);
QUIT
